FILE_TYPE = MACRO_DRAWING;
SET COLOR_WIRE YELLOW;
SET COLOR_PROP ORANGE;
SET COLOR_DOT WHITE;
SET COLOR_ARC YELLOW;
SET COLOR_BODY GREEN;
SET COLOR_NOTE PURPLE;
SET PROP_DISPLAY VALUE;
SET PAGE_NUMBER P411;
FORCEADD Q_RES..2
R 2
(-4475 2475);
FORCEPROP 1 LAST LOCATION R1010
J 2
(-4520 2600);
DISPLAY 0.978723 (-4520 2600);
FORCEPROP 0 LAST $SEC 1
J 0
(-4500 2650);
DISPLAY 0.680851 (-4500 2650);
PAINT MONO (-4500 2650);
DISPLAY INVISIBLE (-4500 2650);
FORCEPROP 0 LAST CDS_SEC 1
J 0
(-4500 2650);
DISPLAY 0.680851 (-4500 2650);
DISPLAY INVISIBLE (-4500 2650);
FORCEPROP 1 LASTPIN (-4475 2575) $PN 1
J 2
(-4480 2537);
DISPLAY 0.787234 (-4480 2537);
PAINT MONO (-4480 2537);
FORCEPROP 1 LASTPIN (-4475 2375) $PN 2
J 2
(-4480 2385);
DISPLAY 0.787234 (-4480 2385);
PAINT MONO (-4480 2385);
FORCEPROP 1 LAST TOLERANCE 5%
J 2
(-4520 2500);
DISPLAY 0.978723 (-4520 2500);
FORCEPROP 1 LAST VALUE 0
J 2
(-4520 2550);
DISPLAY 0.978723 (-4520 2550);
FORCEPROP 1 LAST PACK_TYPE 0603LF
J 2
(-4515 2300);
DISPLAY 0.978723 (-4515 2300);
FORCEPROP 1 LAST WATTAGE 1/4W
J 2
(-4515 2450);
DISPLAY 0.978723 (-4515 2450);
FORCEPROP 1 LAST MATERIAL EMPTY
J 2
(-4515 2400);
DISPLAY 0.978723 (-4515 2400);
FORCEPROP 2 LAST CDS_LIB pure_quanta
J 2
(-4475 2475);
DISPLAY INVISIBLE (-4475 2475);
FORCEPROP 1 LAST PATH I10
J 2
(-4525 2650);
DISPLAY 0.978723 (-4525 2650);
PAINT WHITE (-4525 2650);
DISPLAY INVISIBLE (-4525 2650);
FORCEPROP 1 LAST PART_NUMBER CS00006J900
J 2
(-4515 2350);
DISPLAY 0.978723 (-4515 2350);
DISPLAY INVISIBLE (-4515 2350);
FORCEADD Q_INDUCTOR..1
(-7950 4175);
FORCEPROP 1 LAST LOCATION L13
J 0
(-8075 4335);
DISPLAY 0.723404 (-8075 4335);
PAINT GREEN (-8075 4335);
FORCEPROP 0 LAST $SEC 1
J 0
(-8075 4425);
DISPLAY 0.680851 (-8075 4425);
PAINT MONO (-8075 4425);
DISPLAY INVISIBLE (-8075 4425);
FORCEPROP 0 LAST CDS_SEC 1
J 0
(-8075 4425);
DISPLAY 0.680851 (-8075 4425);
DISPLAY INVISIBLE (-8075 4425);
FORCEPROP 0 LASTPIN (-8050 4150) $PN 1
J 2
(-8060 4160);
DISPLAY 0.680851 (-8060 4160);
PAINT MONO (-8060 4160);
FORCEPROP 0 LASTPIN (-7850 4150) $PN 2
J 0
(-7840 4160);
DISPLAY 0.680851 (-7840 4160);
PAINT MONO (-7840 4160);
FORCEPROP 1 LAST MATERIAL IND
J 0
(-8075 4230);
DISPLAY 0.723404 (-8075 4230);
PAINT GREEN (-8075 4230);
FORCEPROP 2 LAST PACK_TYPE SMLF
J 0
(-8075 4375);
DISPLAY 0.680851 (-8075 4375);
FORCEPROP 2 LAST VALUE BLM21SN300SN1D/5A
J 0
(-8200 4075);
DISPLAY 0.680851 (-8200 4075);
FORCEPROP 1 LAST NEEDS_NO_SIZE TRUE
J 0
(-7950 4175);
DISPLAY 0.468085 (-7950 4175);
PAINT GREEN (-7950 4175);
DISPLAY INVISIBLE (-7950 4175);
FORCEPROP 2 LAST CDS_LIB pure_quanta
J 0
(-7950 4175);
DISPLAY INVISIBLE (-7950 4175);
FORCEPROP 1 LAST PATH I11
J 0
(-7875 4230);
DISPLAY 0.723404 (-7875 4230);
PAINT GREEN (-7875 4230);
DISPLAY INVISIBLE (-7875 4230);
FORCEPROP 1 LAST PART_NUMBER CX300SN1000
J 0
(-8075 4285);
DISPLAY 0.723404 (-8075 4285);
PAINT GREEN (-8075 4285);
DISPLAY INVISIBLE (-8075 4285);
FORCEADD Q_CAP..1
(-7375 3900);
FORCEPROP 1 LAST LOCATION C588
J 0
(-7325 4000);
DISPLAY 0.638298 (-7325 4000);
PAINT WHITE (-7325 4000);
FORCEPROP 0 LAST $SEC 1
J 0
(-7325 4025);
DISPLAY 0.680851 (-7325 4025);
PAINT MONO (-7325 4025);
DISPLAY INVISIBLE (-7325 4025);
FORCEPROP 0 LAST CDS_SEC 1
J 0
(-7325 4025);
DISPLAY 0.680851 (-7325 4025);
DISPLAY INVISIBLE (-7325 4025);
FORCEPROP 1 LASTPIN (-7375 4000) $PN 1
J 0
(-7365 3980);
DISPLAY 0.787234 (-7365 3980);
PAINT MONO (-7365 3980);
FORCEPROP 1 LASTPIN (-7375 3800) $PN 2
J 0
(-7365 3780);
DISPLAY 0.787234 (-7365 3780);
PAINT MONO (-7365 3780);
FORCEPROP 1 LAST VOLTAGE 4V
J 0
(-7325 3900);
DISPLAY 0.510638 (-7325 3900);
FORCEPROP 1 LAST PACK_TYPE C0805
J 0
(-7325 3750);
DISPLAY 0.510638 (-7325 3750);
FORCEPROP 1 LAST VALUE 100UF
J 0
(-7325 3950);
DISPLAY 0.510638 (-7325 3950);
FORCEPROP 1 LAST MATERIAL X6S
J 0
(-7325 3800);
DISPLAY 0.510638 (-7325 3800);
FORCEPROP 1 LAST TOLERANCE 20%
J 0
(-7325 3850);
DISPLAY 0.510638 (-7325 3850);
FORCEPROP 2 LAST CDS_LIB pure_quanta
J 0
(-7375 3900);
DISPLAY INVISIBLE (-7375 3900);
FORCEPROP 1 LAST PATH I12
J 0
(-7325 4050);
DISPLAY 0.978723 (-7325 4050);
PAINT WHITE (-7325 4050);
DISPLAY INVISIBLE (-7325 4050);
FORCEPROP 1 LAST PART_NUMBER CH710KMEA01
J 0
(-7325 3750);
DISPLAY 0.404255 (-7325 3750);
DISPLAY INVISIBLE (-7325 3750);
FORCEADD P1V0..1
(-7475 4375);
FORCEPROP 3 LASTPIN (-7475 4325) SIG_NAME P1V8_CPU0_RT1_1A\g
J 0
(-7465 4335);
DISPLAY 0.659574 (-7465 4335);
PAINT MONO (-7465 4335);
DISPLAY INVISIBLE (-7465 4335);
FORCEPROP 1 LAST HDL_POWER P1V8_CPU0_RT1_1A
J 1
(-7475 4425);
DISPLAY 0.489362 (-7475 4425);
PAINT SKYBLUE (-7475 4425);
FORCEPROP 2 LAST CDS_LIB pure_quanta_power
J 0
(-7475 4375);
DISPLAY INVISIBLE (-7475 4375);
FORCEPROP 1 LAST PATH I13
J 0
(-7425 4400);
DISPLAY 0.872340 (-7425 4400);
PAINT AQUA (-7425 4400);
DISPLAY INVISIBLE (-7425 4400);
FORCEADD P1V0..1
(-8325 5000);
FORCEPROP 3 LASTPIN (-8325 4950) SIG_NAME P1V8_CPU0_RT_1D\g
J 0
(-8315 4960);
DISPLAY 0.659574 (-8315 4960);
PAINT MONO (-8315 4960);
DISPLAY INVISIBLE (-8315 4960);
FORCEPROP 1 LAST HDL_POWER P1V8_CPU0_RT_1D
J 1
(-8325 5050);
DISPLAY 0.489362 (-8325 5050);
PAINT SKYBLUE (-8325 5050);
FORCEPROP 2 LAST CDS_LIB pure_quanta_power
J 0
(-8325 5000);
DISPLAY INVISIBLE (-8325 5000);
FORCEPROP 1 LAST PATH I14
J 0
(-8275 5025);
DISPLAY 0.872340 (-8275 5025);
PAINT AQUA (-8275 5025);
DISPLAY INVISIBLE (-8275 5025);
FORCEADD Q_CAP..1
(-7150 3900);
FORCEPROP 1 LAST LOCATION C590
J 0
(-7100 4000);
DISPLAY 0.638298 (-7100 4000);
PAINT WHITE (-7100 4000);
FORCEPROP 0 LAST $SEC 1
J 0
(-7100 4025);
DISPLAY 0.680851 (-7100 4025);
PAINT MONO (-7100 4025);
DISPLAY INVISIBLE (-7100 4025);
FORCEPROP 0 LAST CDS_SEC 1
J 0
(-7100 4025);
DISPLAY 0.680851 (-7100 4025);
DISPLAY INVISIBLE (-7100 4025);
FORCEPROP 1 LASTPIN (-7150 4000) $PN 1
J 0
(-7140 3980);
DISPLAY 0.787234 (-7140 3980);
PAINT MONO (-7140 3980);
FORCEPROP 1 LASTPIN (-7150 3800) $PN 2
J 0
(-7140 3780);
DISPLAY 0.787234 (-7140 3780);
PAINT MONO (-7140 3780);
FORCEPROP 1 LAST VOLTAGE 4V
J 0
(-7100 3900);
DISPLAY 0.510638 (-7100 3900);
FORCEPROP 1 LAST VALUE 22UF
J 0
(-7100 3950);
DISPLAY 0.510638 (-7100 3950);
FORCEPROP 1 LAST MATERIAL X6S
J 0
(-7100 3800);
DISPLAY 0.510638 (-7100 3800);
FORCEPROP 1 LAST TOLERANCE 20%
J 0
(-7100 3850);
DISPLAY 0.510638 (-7100 3850);
FORCEPROP 1 LAST PACK_TYPE C0402
J 0
(-7100 3750);
DISPLAY 0.510638 (-7100 3750);
FORCEPROP 2 LAST CDS_LIB pure_quanta
J 0
(-7150 3900);
DISPLAY INVISIBLE (-7150 3900);
FORCEPROP 1 LAST PATH I15
J 0
(-7100 4050);
DISPLAY 0.978723 (-7100 4050);
PAINT WHITE (-7100 4050);
DISPLAY INVISIBLE (-7100 4050);
FORCEPROP 1 LAST PART_NUMBER CH622KMEB02
J 0
(-7100 3750);
DISPLAY 0.978723 (-7100 3750);
DISPLAY INVISIBLE (-7100 3750);
FORCEADD Q_CAP..1
(-6950 3900);
FORCEPROP 1 LAST LOCATION C595
J 0
(-6900 4000);
DISPLAY 0.808511 (-6900 4000);
PAINT WHITE (-6900 4000);
FORCEPROP 0 LAST $SEC 1
J 0
(-6900 4050);
DISPLAY 0.680851 (-6900 4050);
PAINT MONO (-6900 4050);
DISPLAY INVISIBLE (-6900 4050);
FORCEPROP 0 LAST CDS_SEC 1
J 0
(-6900 4050);
DISPLAY 0.680851 (-6900 4050);
DISPLAY INVISIBLE (-6900 4050);
FORCEPROP 1 LASTPIN (-6950 4000) $PN 1
J 0
(-6940 3980);
DISPLAY 0.787234 (-6940 3980);
PAINT MONO (-6940 3980);
FORCEPROP 1 LASTPIN (-6950 3800) $PN 2
J 0
(-6940 3780);
DISPLAY 0.787234 (-6940 3780);
PAINT MONO (-6940 3780);
FORCEPROP 1 LAST VOLTAGE 6.3V
J 0
(-6900 3900);
DISPLAY 0.510638 (-6900 3900);
FORCEPROP 1 LAST VALUE 10UF
J 0
(-6900 3950);
DISPLAY 0.510638 (-6900 3950);
FORCEPROP 1 LAST TOLERANCE 20%
J 0
(-6900 3850);
DISPLAY 0.510638 (-6900 3850);
FORCEPROP 1 LAST MATERIAL X6S
J 0
(-6900 3800);
DISPLAY 0.510638 (-6900 3800);
FORCEPROP 1 LAST PACK_TYPE C0402
J 0
(-6900 3750);
DISPLAY 0.510638 (-6900 3750);
FORCEPROP 2 LAST CDS_LIB pure_quanta
J 0
(-6950 3900);
DISPLAY INVISIBLE (-6950 3900);
FORCEPROP 1 LAST PATH I16
J 0
(-6900 4050);
DISPLAY 0.978723 (-6900 4050);
PAINT WHITE (-6900 4050);
DISPLAY INVISIBLE (-6900 4050);
FORCEPROP 1 LAST PART_NUMBER CH6101MEB01
J 0
(-6900 3750);
DISPLAY 0.978723 (-6900 3750);
DISPLAY INVISIBLE (-6900 3750);
FORCEADD Q_CAP..1
(-7225 4725);
FORCEPROP 1 LAST LOCATION C587
J 0
(-7175 4825);
DISPLAY 0.638298 (-7175 4825);
PAINT WHITE (-7175 4825);
FORCEPROP 0 LAST $SEC 1
J 0
(-7175 4875);
DISPLAY 0.680851 (-7175 4875);
PAINT MONO (-7175 4875);
DISPLAY INVISIBLE (-7175 4875);
FORCEPROP 0 LAST CDS_SEC 1
J 0
(-7175 4875);
DISPLAY 0.680851 (-7175 4875);
DISPLAY INVISIBLE (-7175 4875);
FORCEPROP 1 LASTPIN (-7225 4825) $PN 1
J 0
(-7215 4805);
DISPLAY 0.787234 (-7215 4805);
PAINT MONO (-7215 4805);
FORCEPROP 1 LASTPIN (-7225 4625) $PN 2
J 0
(-7215 4605);
DISPLAY 0.787234 (-7215 4605);
PAINT MONO (-7215 4605);
FORCEPROP 1 LAST VALUE 100UF
J 0
(-7175 4775);
DISPLAY 0.510638 (-7175 4775);
FORCEPROP 1 LAST VOLTAGE 4V
J 0
(-7175 4725);
DISPLAY 0.510638 (-7175 4725);
FORCEPROP 1 LAST TOLERANCE 20%
J 0
(-7175 4675);
DISPLAY 0.510638 (-7175 4675);
FORCEPROP 1 LAST MATERIAL X6S
J 0
(-7175 4625);
DISPLAY 0.510638 (-7175 4625);
FORCEPROP 1 LAST PACK_TYPE C0805
J 0
(-7175 4575);
DISPLAY 0.510638 (-7175 4575);
FORCEPROP 2 LAST CDS_LIB pure_quanta
J 0
(-7225 4725);
DISPLAY INVISIBLE (-7225 4725);
FORCEPROP 1 LAST PATH I17
J 0
(-7175 4875);
DISPLAY 0.978723 (-7175 4875);
PAINT WHITE (-7175 4875);
DISPLAY INVISIBLE (-7175 4875);
FORCEPROP 1 LAST PART_NUMBER CH710KMEA01
J 0
(-7175 4575);
DISPLAY 0.404255 (-7175 4575);
DISPLAY INVISIBLE (-7175 4575);
FORCEADD Q_CAP..1
(-6975 4725);
FORCEPROP 1 LAST LOCATION C589
J 0
(-6925 4825);
DISPLAY 0.510638 (-6925 4825);
PAINT WHITE (-6925 4825);
FORCEPROP 0 LAST $SEC 1
J 0
(-6925 4850);
DISPLAY 0.680851 (-6925 4850);
PAINT MONO (-6925 4850);
DISPLAY INVISIBLE (-6925 4850);
FORCEPROP 0 LAST CDS_SEC 1
J 0
(-6925 4850);
DISPLAY 0.680851 (-6925 4850);
DISPLAY INVISIBLE (-6925 4850);
FORCEPROP 1 LASTPIN (-6975 4825) $PN 1
J 0
(-6965 4805);
DISPLAY 0.787234 (-6965 4805);
PAINT MONO (-6965 4805);
FORCEPROP 1 LASTPIN (-6975 4625) $PN 2
J 0
(-6965 4605);
DISPLAY 0.787234 (-6965 4605);
PAINT MONO (-6965 4605);
FORCEPROP 1 LAST TOLERANCE 20%
J 0
(-6925 4675);
DISPLAY 0.510638 (-6925 4675);
FORCEPROP 1 LAST PACK_TYPE C0402
J 0
(-6925 4575);
DISPLAY 0.510638 (-6925 4575);
FORCEPROP 1 LAST MATERIAL X6S
J 0
(-6925 4625);
DISPLAY 0.510638 (-6925 4625);
FORCEPROP 1 LAST VALUE 22UF
J 0
(-6925 4775);
DISPLAY 0.510638 (-6925 4775);
FORCEPROP 1 LAST VOLTAGE 4V
J 0
(-6925 4725);
DISPLAY 0.510638 (-6925 4725);
FORCEPROP 2 LAST CDS_LIB pure_quanta
J 0
(-6975 4725);
DISPLAY INVISIBLE (-6975 4725);
FORCEPROP 1 LAST PATH I18
J 0
(-6925 4875);
DISPLAY 0.978723 (-6925 4875);
PAINT WHITE (-6925 4875);
DISPLAY INVISIBLE (-6925 4875);
FORCEPROP 1 LAST PART_NUMBER CH622KMEB02
J 0
(-6925 4575);
DISPLAY 0.978723 (-6925 4575);
DISPLAY INVISIBLE (-6925 4575);
FORCEADD Q_CAP..1
(-6750 3900);
FORCEPROP 1 LAST LOCATION C594
J 0
(-6700 4000);
DISPLAY 0.638298 (-6700 4000);
PAINT WHITE (-6700 4000);
FORCEPROP 0 LAST $SEC 1
J 0
(-6700 4025);
DISPLAY 0.680851 (-6700 4025);
PAINT MONO (-6700 4025);
DISPLAY INVISIBLE (-6700 4025);
FORCEPROP 0 LAST CDS_SEC 1
J 0
(-6700 4025);
DISPLAY 0.680851 (-6700 4025);
DISPLAY INVISIBLE (-6700 4025);
FORCEPROP 1 LASTPIN (-6750 4000) $PN 1
J 0
(-6740 3980);
DISPLAY 0.787234 (-6740 3980);
PAINT MONO (-6740 3980);
FORCEPROP 1 LASTPIN (-6750 3800) $PN 2
J 0
(-6740 3780);
DISPLAY 0.787234 (-6740 3780);
PAINT MONO (-6740 3780);
FORCEPROP 1 LAST VALUE 4.7UF
J 0
(-6700 3950);
DISPLAY 0.510638 (-6700 3950);
FORCEPROP 1 LAST VOLTAGE 6.3V
J 0
(-6700 3900);
DISPLAY 0.510638 (-6700 3900);
FORCEPROP 1 LAST TOLERANCE 20%
J 0
(-6700 3850);
DISPLAY 0.510638 (-6700 3850);
FORCEPROP 1 LAST MATERIAL X6S
J 0
(-6700 3800);
DISPLAY 0.510638 (-6700 3800);
FORCEPROP 1 LAST PACK_TYPE 0402
J 0
(-6700 3750);
DISPLAY 0.510638 (-6700 3750);
FORCEPROP 2 LAST CDS_LIB pure_quanta
J 0
(-6750 3900);
DISPLAY INVISIBLE (-6750 3900);
FORCEPROP 1 LAST PATH I19
J 0
(-6700 4050);
DISPLAY 0.978723 (-6700 4050);
PAINT WHITE (-6700 4050);
DISPLAY INVISIBLE (-6700 4050);
FORCEPROP 1 LAST PART_NUMBER CH5471MEB01
J 0
(-6700 3750);
DISPLAY 0.978723 (-6700 3750);
DISPLAY INVISIBLE (-6700 3750);
FORCEADD Q_RES..1
(-7875 3275);
FORCEPROP 1 LAST LOCATION R1003
J 0
(-8150 3275);
DISPLAY 0.787234 (-8150 3275);
FORCEPROP 2 LAST SEC 1
J 0
(-7925 3475);
DISPLAY 0.680851 (-7925 3475);
PAINT MONO (-7925 3475);
DISPLAY INVISIBLE (-7925 3475);
FORCEPROP 1 LASTPIN (-7975 3275) $PN 1
J 0
(-7963 3287);
DISPLAY 0.787234 (-7963 3287);
PAINT MONO (-7963 3287);
FORCEPROP 1 LASTPIN (-7775 3275) $PN 2
J 0
(-7813 3287);
DISPLAY 0.787234 (-7813 3287);
PAINT MONO (-7813 3287);
FORCEPROP 1 LAST VALUE 0
J 2
(-7725 3300);
DISPLAY 0.638298 (-7725 3300);
FORCEPROP 1 LAST TOLERANCE 5%
J 0
(-7825 3225);
DISPLAY 0.638298 (-7825 3225);
FORCEPROP 1 LAST MATERIAL EMPTY
J 0
(-7850 3175);
DISPLAY 0.638298 (-7850 3175);
FORCEPROP 1 LAST WATTAGE 1/16W
J 2
(-7875 3175);
DISPLAY 0.638298 (-7875 3175);
FORCEPROP 1 LAST PACK_TYPE 0402LF
J 0
(-8025 3225);
DISPLAY 0.638298 (-8025 3225);
FORCEPROP 2 LAST SEC_TYPE 0402LF
J 0
(-7925 3475);
DISPLAY 0.680851 (-7925 3475);
DISPLAY INVISIBLE (-7925 3475);
FORCEPROP 2 LAST CDS_LIB pure_quanta
J 0
(-7875 3275);
DISPLAY INVISIBLE (-7875 3275);
FORCEPROP 1 LAST PATH I2
J 0
(-7925 3425);
DISPLAY 0.978723 (-7925 3425);
PAINT WHITE (-7925 3425);
DISPLAY INVISIBLE (-7925 3425);
FORCEPROP 1 LAST PART_NUMBER CS00002JB13
J 0
(-7925 3375);
DISPLAY 0.978723 (-7925 3375);
DISPLAY INVISIBLE (-7925 3375);
FORCEADD Q_CAP..1
(-6525 3900);
FORCEPROP 1 LAST LOCATION C597
J 0
(-6475 4000);
DISPLAY 0.808511 (-6475 4000);
PAINT WHITE (-6475 4000);
FORCEPROP 0 LAST $SEC 1
J 0
(-6475 4050);
DISPLAY 0.680851 (-6475 4050);
PAINT MONO (-6475 4050);
DISPLAY INVISIBLE (-6475 4050);
FORCEPROP 0 LAST CDS_SEC 1
J 0
(-6475 4050);
DISPLAY 0.680851 (-6475 4050);
DISPLAY INVISIBLE (-6475 4050);
FORCEPROP 1 LASTPIN (-6525 4000) $PN 1
J 0
(-6515 3980);
DISPLAY 0.787234 (-6515 3980);
PAINT MONO (-6515 3980);
FORCEPROP 1 LASTPIN (-6525 3800) $PN 2
J 0
(-6515 3780);
DISPLAY 0.787234 (-6515 3780);
PAINT MONO (-6515 3780);
FORCEPROP 1 LAST VOLTAGE 4V
J 0
(-6475 3900);
DISPLAY 0.510638 (-6475 3900);
FORCEPROP 1 LAST MATERIAL X6S
J 0
(-6475 3800);
DISPLAY 0.510638 (-6475 3800);
FORCEPROP 1 LAST PACK_TYPE 0201
J 0
(-6475 3750);
DISPLAY 0.510638 (-6475 3750);
FORCEPROP 1 LAST TOLERANCE 20%
J 0
(-6475 3850);
DISPLAY 0.510638 (-6475 3850);
FORCEPROP 1 LAST VALUE 1UF
J 0
(-6475 3950);
DISPLAY 0.510638 (-6475 3950);
FORCEPROP 2 LAST CDS_LIB pure_quanta
J 0
(-6525 3900);
DISPLAY INVISIBLE (-6525 3900);
FORCEPROP 1 LAST PATH I20
J 0
(-6475 4050);
DISPLAY 0.978723 (-6475 4050);
PAINT WHITE (-6475 4050);
DISPLAY INVISIBLE (-6475 4050);
FORCEPROP 1 LAST PART_NUMBER CH-10KMEE00
J 0
(-6475 3750);
DISPLAY 0.510638 (-6475 3750);
DISPLAY INVISIBLE (-6475 3750);
FORCEADD Q_CAP..1
(-6325 3900);
FORCEPROP 1 LAST LOCATION C599
J 0
(-6275 4000);
DISPLAY 0.808511 (-6275 4000);
PAINT WHITE (-6275 4000);
FORCEPROP 0 LAST $SEC 1
J 0
(-6275 4050);
DISPLAY 0.680851 (-6275 4050);
PAINT MONO (-6275 4050);
DISPLAY INVISIBLE (-6275 4050);
FORCEPROP 0 LAST CDS_SEC 1
J 0
(-6275 4050);
DISPLAY 0.680851 (-6275 4050);
DISPLAY INVISIBLE (-6275 4050);
FORCEPROP 1 LASTPIN (-6325 4000) $PN 1
J 0
(-6315 3980);
DISPLAY 0.787234 (-6315 3980);
PAINT MONO (-6315 3980);
FORCEPROP 1 LASTPIN (-6325 3800) $PN 2
J 0
(-6315 3780);
DISPLAY 0.787234 (-6315 3780);
PAINT MONO (-6315 3780);
FORCEPROP 1 LAST MATERIAL X6S
J 0
(-6275 3800);
DISPLAY 0.510638 (-6275 3800);
FORCEPROP 1 LAST PACK_TYPE 0201
J 0
(-6275 3750);
DISPLAY 0.510638 (-6275 3750);
FORCEPROP 1 LAST VALUE 1UF
J 0
(-6275 3950);
DISPLAY 0.510638 (-6275 3950);
FORCEPROP 1 LAST VOLTAGE 4V
J 0
(-6275 3900);
DISPLAY 0.510638 (-6275 3900);
FORCEPROP 1 LAST TOLERANCE 20%
J 0
(-6275 3850);
DISPLAY 0.510638 (-6275 3850);
FORCEPROP 2 LAST CDS_LIB pure_quanta
J 0
(-6325 3900);
DISPLAY INVISIBLE (-6325 3900);
FORCEPROP 1 LAST PATH I21
J 0
(-6275 4050);
DISPLAY 0.978723 (-6275 4050);
PAINT WHITE (-6275 4050);
DISPLAY INVISIBLE (-6275 4050);
FORCEPROP 1 LAST PART_NUMBER CH-10KMEE00
J 0
(-6275 3750);
DISPLAY 0.510638 (-6275 3750);
DISPLAY INVISIBLE (-6275 3750);
FORCEADD Q_CAP..1
(-6725 4700);
FORCEPROP 1 LAST LOCATION C591
J 0
(-6675 4800);
DISPLAY 0.638298 (-6675 4800);
PAINT WHITE (-6675 4800);
FORCEPROP 0 LAST $SEC 1
J 0
(-6675 4850);
DISPLAY 0.680851 (-6675 4850);
PAINT MONO (-6675 4850);
DISPLAY INVISIBLE (-6675 4850);
FORCEPROP 0 LAST CDS_SEC 1
J 0
(-6675 4850);
DISPLAY 0.680851 (-6675 4850);
DISPLAY INVISIBLE (-6675 4850);
FORCEPROP 1 LASTPIN (-6725 4800) $PN 1
J 0
(-6715 4780);
DISPLAY 0.787234 (-6715 4780);
PAINT MONO (-6715 4780);
FORCEPROP 1 LASTPIN (-6725 4600) $PN 2
J 0
(-6715 4580);
DISPLAY 0.787234 (-6715 4580);
PAINT MONO (-6715 4580);
FORCEPROP 1 LAST PACK_TYPE C0402
J 0
(-6675 4550);
DISPLAY 0.510638 (-6675 4550);
FORCEPROP 1 LAST MATERIAL X6S
J 0
(-6675 4600);
DISPLAY 0.510638 (-6675 4600);
FORCEPROP 1 LAST TOLERANCE 20%
J 0
(-6675 4650);
DISPLAY 0.510638 (-6675 4650);
FORCEPROP 1 LAST VOLTAGE 6.3V
J 0
(-6675 4700);
DISPLAY 0.510638 (-6675 4700);
FORCEPROP 1 LAST VALUE 10UF
J 0
(-6675 4750);
DISPLAY 0.510638 (-6675 4750);
FORCEPROP 2 LAST CDS_LIB pure_quanta
J 0
(-6725 4700);
DISPLAY INVISIBLE (-6725 4700);
FORCEPROP 1 LAST PATH I22
J 0
(-6675 4850);
DISPLAY 0.978723 (-6675 4850);
PAINT WHITE (-6675 4850);
DISPLAY INVISIBLE (-6675 4850);
FORCEPROP 1 LAST PART_NUMBER CH6101MEB01
J 0
(-6675 4550);
DISPLAY 0.978723 (-6675 4550);
DISPLAY INVISIBLE (-6675 4550);
FORCEADD UNIVERSAL_GND..1
(-6550 4425);
FORCEPROP 3 LASTPIN (-6550 4475) SIG_NAME GND\g
J 0
(-6540 4485);
DISPLAY 0.659574 (-6540 4485);
PAINT MONO (-6540 4485);
DISPLAY INVISIBLE (-6540 4485);
FORCEPROP 2 LAST CDS_LIB pure_quanta_power
J 0
(-6550 4425);
DISPLAY INVISIBLE (-6550 4425);
FORCEPROP 1 LAST HDL_POWER GND
J 1
(-6525 4350);
DISPLAY 0.872340 (-6525 4350);
PAINT GREEN (-6525 4350);
DISPLAY INVISIBLE (-6525 4350);
FORCEPROP 1 LAST PATH I23
J 0
(-6475 4425);
DISPLAY 0.872340 (-6475 4425);
PAINT AQUA (-6475 4425);
DISPLAY INVISIBLE (-6475 4425);
FORCEADD Q_CAP..1
(-6475 4700);
FORCEPROP 1 LAST LOCATION C596
J 0
(-6425 4800);
DISPLAY 0.638298 (-6425 4800);
PAINT WHITE (-6425 4800);
FORCEPROP 0 LAST $SEC 1
J 0
(-6425 4850);
DISPLAY 0.680851 (-6425 4850);
PAINT MONO (-6425 4850);
DISPLAY INVISIBLE (-6425 4850);
FORCEPROP 0 LAST CDS_SEC 1
J 0
(-6425 4850);
DISPLAY 0.680851 (-6425 4850);
DISPLAY INVISIBLE (-6425 4850);
FORCEPROP 1 LASTPIN (-6475 4800) $PN 1
J 0
(-6465 4780);
DISPLAY 0.787234 (-6465 4780);
PAINT MONO (-6465 4780);
FORCEPROP 1 LASTPIN (-6475 4600) $PN 2
J 0
(-6465 4580);
DISPLAY 0.787234 (-6465 4580);
PAINT MONO (-6465 4580);
FORCEPROP 1 LAST VOLTAGE 6.3V
J 0
(-6425 4700);
DISPLAY 0.510638 (-6425 4700);
FORCEPROP 1 LAST TOLERANCE 20%
J 0
(-6425 4650);
DISPLAY 0.510638 (-6425 4650);
FORCEPROP 1 LAST MATERIAL X6S
J 0
(-6425 4600);
DISPLAY 0.510638 (-6425 4600);
FORCEPROP 1 LAST VALUE 4.7UF
J 0
(-6425 4750);
DISPLAY 0.510638 (-6425 4750);
FORCEPROP 1 LAST PACK_TYPE 0402
J 0
(-6425 4550);
DISPLAY 0.510638 (-6425 4550);
FORCEPROP 2 LAST CDS_LIB pure_quanta
J 0
(-6475 4700);
DISPLAY INVISIBLE (-6475 4700);
FORCEPROP 1 LAST PATH I24
J 0
(-6425 4850);
DISPLAY 0.978723 (-6425 4850);
PAINT WHITE (-6425 4850);
DISPLAY INVISIBLE (-6425 4850);
FORCEPROP 1 LAST PART_NUMBER CH5471MEB01
J 0
(-6425 4550);
DISPLAY 0.978723 (-6425 4550);
DISPLAY INVISIBLE (-6425 4550);
FORCEADD Q_CAP..1
(-6100 3900);
FORCEPROP 1 LAST LOCATION C600
J 0
(-6050 4000);
DISPLAY 0.978723 (-6050 4000);
PAINT WHITE (-6050 4000);
FORCEPROP 0 LAST $SEC 1
J 0
(-6050 4050);
DISPLAY 0.680851 (-6050 4050);
PAINT MONO (-6050 4050);
DISPLAY INVISIBLE (-6050 4050);
FORCEPROP 0 LAST CDS_SEC 1
J 0
(-6050 4050);
DISPLAY 0.680851 (-6050 4050);
DISPLAY INVISIBLE (-6050 4050);
FORCEPROP 1 LASTPIN (-6100 4000) $PN 1
J 0
(-6090 3980);
DISPLAY 0.787234 (-6090 3980);
PAINT MONO (-6090 3980);
FORCEPROP 1 LASTPIN (-6100 3800) $PN 2
J 0
(-6090 3780);
DISPLAY 0.787234 (-6090 3780);
PAINT MONO (-6090 3780);
FORCEPROP 1 LAST TOLERANCE 10%
J 0
(-6050 3850);
DISPLAY 0.638298 (-6050 3850);
FORCEPROP 1 LAST VALUE 0.1UF
J 0
(-6050 3950);
DISPLAY 0.638298 (-6050 3950);
FORCEPROP 1 LAST MATERIAL X7S
J 0
(-6050 3800);
DISPLAY 0.638298 (-6050 3800);
FORCEPROP 1 LAST VOLTAGE 10V
J 0
(-6050 3900);
DISPLAY 0.638298 (-6050 3900);
FORCEPROP 1 LAST PACK_TYPE C0201
J 0
(-6050 3750);
DISPLAY 0.638298 (-6050 3750);
FORCEPROP 2 LAST CDS_LIB pure_quanta
J 0
(-6100 3900);
DISPLAY INVISIBLE (-6100 3900);
FORCEPROP 1 LAST PATH I25
J 0
(-6050 4050);
DISPLAY 0.978723 (-6050 4050);
PAINT WHITE (-6050 4050);
DISPLAY INVISIBLE (-6050 4050);
FORCEPROP 1 LAST PART_NUMBER CH4102K6E00
J 0
(-6050 3750);
DISPLAY 0.978723 (-6050 3750);
DISPLAY INVISIBLE (-6050 3750);
FORCEADD Q_CAP..1
(-5850 3900);
FORCEPROP 1 LAST LOCATION C602
J 0
(-5800 4000);
DISPLAY 0.978723 (-5800 4000);
PAINT WHITE (-5800 4000);
FORCEPROP 0 LAST $SEC 1
J 0
(-5800 4050);
DISPLAY 0.680851 (-5800 4050);
PAINT MONO (-5800 4050);
DISPLAY INVISIBLE (-5800 4050);
FORCEPROP 0 LAST CDS_SEC 1
J 0
(-5800 4050);
DISPLAY 0.680851 (-5800 4050);
DISPLAY INVISIBLE (-5800 4050);
FORCEPROP 1 LASTPIN (-5850 4000) $PN 1
J 0
(-5840 3980);
DISPLAY 0.787234 (-5840 3980);
PAINT MONO (-5840 3980);
FORCEPROP 1 LASTPIN (-5850 3800) $PN 2
J 0
(-5840 3780);
DISPLAY 0.787234 (-5840 3780);
PAINT MONO (-5840 3780);
FORCEPROP 1 LAST VALUE 0.1UF
J 0
(-5800 3950);
DISPLAY 0.638298 (-5800 3950);
FORCEPROP 1 LAST VOLTAGE 10V
J 0
(-5800 3900);
DISPLAY 0.638298 (-5800 3900);
FORCEPROP 1 LAST TOLERANCE 10%
J 0
(-5800 3850);
DISPLAY 0.638298 (-5800 3850);
FORCEPROP 1 LAST PACK_TYPE C0201
J 0
(-5800 3750);
DISPLAY 0.638298 (-5800 3750);
FORCEPROP 1 LAST MATERIAL X7S
J 0
(-5800 3800);
DISPLAY 0.638298 (-5800 3800);
FORCEPROP 2 LAST CDS_LIB pure_quanta
J 0
(-5850 3900);
DISPLAY INVISIBLE (-5850 3900);
FORCEPROP 1 LAST PATH I26
J 0
(-5800 4050);
DISPLAY 0.978723 (-5800 4050);
PAINT WHITE (-5800 4050);
DISPLAY INVISIBLE (-5800 4050);
FORCEPROP 1 LAST PART_NUMBER CH4102K6E00
J 0
(-5800 3750);
DISPLAY 0.978723 (-5800 3750);
DISPLAY INVISIBLE (-5800 3750);
FORCEADD Q_CAP..1
(-5600 3900);
FORCEPROP 1 LAST LOCATION C603
J 0
(-5550 4000);
DISPLAY 0.978723 (-5550 4000);
PAINT WHITE (-5550 4000);
FORCEPROP 0 LAST $SEC 1
J 0
(-5550 4050);
DISPLAY 0.680851 (-5550 4050);
PAINT MONO (-5550 4050);
DISPLAY INVISIBLE (-5550 4050);
FORCEPROP 0 LAST CDS_SEC 1
J 0
(-5550 4050);
DISPLAY 0.680851 (-5550 4050);
DISPLAY INVISIBLE (-5550 4050);
FORCEPROP 1 LASTPIN (-5600 4000) $PN 1
J 0
(-5590 3980);
DISPLAY 0.787234 (-5590 3980);
PAINT MONO (-5590 3980);
FORCEPROP 1 LASTPIN (-5600 3800) $PN 2
J 0
(-5590 3780);
DISPLAY 0.787234 (-5590 3780);
PAINT MONO (-5590 3780);
FORCEPROP 1 LAST PACK_TYPE C0201
J 0
(-5550 3750);
DISPLAY 0.638298 (-5550 3750);
FORCEPROP 1 LAST MATERIAL X7S
J 0
(-5550 3800);
DISPLAY 0.638298 (-5550 3800);
FORCEPROP 1 LAST TOLERANCE 10%
J 0
(-5550 3850);
DISPLAY 0.638298 (-5550 3850);
FORCEPROP 1 LAST VOLTAGE 10V
J 0
(-5550 3900);
DISPLAY 0.638298 (-5550 3900);
FORCEPROP 1 LAST VALUE 0.1UF
J 0
(-5550 3950);
DISPLAY 0.638298 (-5550 3950);
FORCEPROP 2 LAST CDS_LIB pure_quanta
J 0
(-5600 3900);
DISPLAY INVISIBLE (-5600 3900);
FORCEPROP 1 LAST PATH I27
J 0
(-5550 4050);
DISPLAY 0.978723 (-5550 4050);
PAINT WHITE (-5550 4050);
DISPLAY INVISIBLE (-5550 4050);
FORCEPROP 1 LAST PART_NUMBER CH4102K6E00
J 0
(-5550 3750);
DISPLAY 0.978723 (-5550 3750);
DISPLAY INVISIBLE (-5550 3750);
FORCEADD Q_CAP..1
(-5325 3900);
FORCEPROP 1 LAST LOCATION C606
J 0
(-5275 4000);
DISPLAY 0.978723 (-5275 4000);
PAINT WHITE (-5275 4000);
FORCEPROP 0 LAST $SEC 1
J 0
(-5275 4050);
DISPLAY 0.680851 (-5275 4050);
PAINT MONO (-5275 4050);
DISPLAY INVISIBLE (-5275 4050);
FORCEPROP 0 LAST CDS_SEC 1
J 0
(-5275 4050);
DISPLAY 0.680851 (-5275 4050);
DISPLAY INVISIBLE (-5275 4050);
FORCEPROP 1 LASTPIN (-5325 4000) $PN 1
J 0
(-5315 3980);
DISPLAY 0.787234 (-5315 3980);
PAINT MONO (-5315 3980);
FORCEPROP 1 LASTPIN (-5325 3800) $PN 2
J 0
(-5315 3780);
DISPLAY 0.787234 (-5315 3780);
PAINT MONO (-5315 3780);
FORCEPROP 1 LAST PACK_TYPE C0201
J 0
(-5275 3750);
DISPLAY 0.638298 (-5275 3750);
FORCEPROP 1 LAST TOLERANCE 10%
J 0
(-5275 3850);
DISPLAY 0.638298 (-5275 3850);
FORCEPROP 1 LAST VOLTAGE 10V
J 0
(-5275 3900);
DISPLAY 0.638298 (-5275 3900);
FORCEPROP 1 LAST VALUE 0.1UF
J 0
(-5275 3950);
DISPLAY 0.638298 (-5275 3950);
FORCEPROP 1 LAST MATERIAL X7S
J 0
(-5275 3800);
DISPLAY 0.638298 (-5275 3800);
FORCEPROP 2 LAST CDS_LIB pure_quanta
J 0
(-5325 3900);
DISPLAY INVISIBLE (-5325 3900);
FORCEPROP 1 LAST PATH I28
J 0
(-5275 4050);
DISPLAY 0.978723 (-5275 4050);
PAINT WHITE (-5275 4050);
DISPLAY INVISIBLE (-5275 4050);
FORCEPROP 1 LAST PART_NUMBER CH4102K6E00
J 0
(-5275 3750);
DISPLAY 0.978723 (-5275 3750);
DISPLAY INVISIBLE (-5275 3750);
FORCEADD VCC_CORE..1
(-4475 5675);
FORCEPROP 3 LASTPIN (-4475 5625) SIG_NAME P0V9_CPU0_RT_2D\g
J 0
(-4465 5635);
DISPLAY 0.659574 (-4465 5635);
PAINT MONO (-4465 5635);
DISPLAY INVISIBLE (-4465 5635);
FORCEPROP 1 LAST HDL_POWER P0V9_CPU0_RT_2D
J 1
(-4475 5725);
DISPLAY 0.617021 (-4475 5725);
PAINT GREEN (-4475 5725);
FORCEPROP 2 LAST CDS_LIB pure_quanta_power
J 0
(-4475 5675);
DISPLAY INVISIBLE (-4475 5675);
FORCEPROP 1 LAST PATH I29
J 0
(-4425 5700);
DISPLAY 0.872340 (-4425 5700);
PAINT AQUA (-4425 5700);
DISPLAY INVISIBLE (-4425 5700);
FORCEADD VCC_CORE..1
(-3325 1375);
FORCEPROP 3 LASTPIN (-3325 1325) SIG_NAME P0V9_CPU0_RT1_2A_2D\g
J 0
(-3315 1335);
DISPLAY 0.659574 (-3315 1335);
PAINT MONO (-3315 1335);
DISPLAY INVISIBLE (-3315 1335);
FORCEPROP 1 LAST HDL_POWER P0V9_CPU0_RT1_2A_2D
J 1
(-3325 1425);
DISPLAY 0.617021 (-3325 1425);
PAINT GREEN (-3325 1425);
FORCEPROP 2 LAST CDS_LIB pure_quanta_power
J 0
(-3325 1375);
DISPLAY INVISIBLE (-3325 1375);
FORCEPROP 1 LAST PATH I30
J 0
(-3275 1400);
DISPLAY 0.872340 (-3275 1400);
PAINT AQUA (-3275 1400);
DISPLAY INVISIBLE (-3275 1400);
FORCEADD UNIVERSAL_GND..1
(-2500 525);
FORCEPROP 3 LASTPIN (-2500 575) SIG_NAME GND\g
J 0
(-2490 585);
DISPLAY 0.659574 (-2490 585);
PAINT MONO (-2490 585);
DISPLAY INVISIBLE (-2490 585);
FORCEPROP 2 LAST CDS_LIB pure_quanta_power
J 0
(-2500 525);
DISPLAY INVISIBLE (-2500 525);
FORCEPROP 1 LAST HDL_POWER GND
J 1
(-2475 450);
DISPLAY 0.872340 (-2475 450);
PAINT GREEN (-2475 450);
DISPLAY INVISIBLE (-2475 450);
FORCEPROP 1 LAST PATH I31
J 0
(-2425 525);
DISPLAY 0.872340 (-2425 525);
PAINT AQUA (-2425 525);
DISPLAY INVISIBLE (-2425 525);
FORCEADD Q_CAP..1
(-3200 850);
FORCEPROP 1 LAST LOCATION C617
J 0
(-3150 950);
DISPLAY 0.978723 (-3150 950);
PAINT WHITE (-3150 950);
FORCEPROP 0 LAST $SEC 1
J 0
(-3150 1000);
DISPLAY 0.680851 (-3150 1000);
PAINT MONO (-3150 1000);
DISPLAY INVISIBLE (-3150 1000);
FORCEPROP 0 LAST CDS_SEC 1
J 0
(-3150 1000);
DISPLAY 0.680851 (-3150 1000);
DISPLAY INVISIBLE (-3150 1000);
FORCEPROP 1 LASTPIN (-3200 950) $PN 1
J 0
(-3190 930);
DISPLAY 0.787234 (-3190 930);
PAINT MONO (-3190 930);
FORCEPROP 1 LASTPIN (-3200 750) $PN 2
J 0
(-3190 730);
DISPLAY 0.787234 (-3190 730);
PAINT MONO (-3190 730);
FORCEPROP 1 LAST PACK_TYPE C0201
J 0
(-3150 700);
DISPLAY 0.638298 (-3150 700);
FORCEPROP 1 LAST MATERIAL X7S
J 0
(-3150 750);
DISPLAY 0.638298 (-3150 750);
FORCEPROP 1 LAST VALUE 0.1UF
J 0
(-3150 900);
DISPLAY 0.638298 (-3150 900);
FORCEPROP 1 LAST TOLERANCE 10%
J 0
(-3150 800);
DISPLAY 0.638298 (-3150 800);
FORCEPROP 1 LAST VOLTAGE 10V
J 0
(-3150 850);
DISPLAY 0.638298 (-3150 850);
FORCEPROP 2 LAST CDS_LIB pure_quanta
J 0
(-3200 850);
DISPLAY INVISIBLE (-3200 850);
FORCEPROP 1 LAST PATH I32
J 0
(-3150 1000);
DISPLAY 0.978723 (-3150 1000);
PAINT WHITE (-3150 1000);
DISPLAY INVISIBLE (-3150 1000);
FORCEPROP 1 LAST PART_NUMBER CH4102K6E00
J 0
(-3150 700);
DISPLAY 0.978723 (-3150 700);
DISPLAY INVISIBLE (-3150 700);
FORCEADD Q_CAP..1
(-2650 850);
FORCEPROP 1 LAST LOCATION C623
J 0
(-2600 950);
DISPLAY 0.978723 (-2600 950);
PAINT WHITE (-2600 950);
FORCEPROP 0 LAST $SEC 1
J 0
(-2600 1000);
DISPLAY 0.680851 (-2600 1000);
PAINT MONO (-2600 1000);
DISPLAY INVISIBLE (-2600 1000);
FORCEPROP 0 LAST CDS_SEC 1
J 0
(-2600 1000);
DISPLAY 0.680851 (-2600 1000);
DISPLAY INVISIBLE (-2600 1000);
FORCEPROP 1 LASTPIN (-2650 950) $PN 1
J 0
(-2640 930);
DISPLAY 0.787234 (-2640 930);
PAINT MONO (-2640 930);
FORCEPROP 1 LASTPIN (-2650 750) $PN 2
J 0
(-2640 730);
DISPLAY 0.787234 (-2640 730);
PAINT MONO (-2640 730);
FORCEPROP 1 LAST MATERIAL X7S
J 0
(-2600 750);
DISPLAY 0.638298 (-2600 750);
FORCEPROP 1 LAST TOLERANCE 10%
J 0
(-2600 800);
DISPLAY 0.638298 (-2600 800);
FORCEPROP 1 LAST PACK_TYPE C0201
J 0
(-2600 700);
DISPLAY 0.638298 (-2600 700);
FORCEPROP 1 LAST VALUE 0.1UF
J 0
(-2600 900);
DISPLAY 0.638298 (-2600 900);
FORCEPROP 1 LAST VOLTAGE 10V
J 0
(-2600 850);
DISPLAY 0.638298 (-2600 850);
FORCEPROP 2 LAST CDS_LIB pure_quanta
J 0
(-2650 850);
DISPLAY INVISIBLE (-2650 850);
FORCEPROP 1 LAST PATH I34
J 0
(-2600 1000);
DISPLAY 0.978723 (-2600 1000);
PAINT WHITE (-2600 1000);
DISPLAY INVISIBLE (-2600 1000);
FORCEPROP 1 LAST PART_NUMBER CH4102K6E00
J 0
(-2600 700);
DISPLAY 0.978723 (-2600 700);
DISPLAY INVISIBLE (-2600 700);
FORCEADD Q_RES..1
(-4100 2200);
FORCEPROP 1 LAST LOCATION R1011
J 0
(-4150 2250);
DISPLAY 0.978723 (-4150 2250);
FORCEPROP 0 LAST $SEC 1
J 0
(-4150 2300);
DISPLAY 0.680851 (-4150 2300);
PAINT MONO (-4150 2300);
DISPLAY INVISIBLE (-4150 2300);
FORCEPROP 0 LAST CDS_SEC 1
J 0
(-4150 2300);
DISPLAY 0.680851 (-4150 2300);
DISPLAY INVISIBLE (-4150 2300);
FORCEPROP 1 LASTPIN (-4200 2200) $PN 1
J 0
(-4188 2212);
DISPLAY 0.787234 (-4188 2212);
PAINT MONO (-4188 2212);
FORCEPROP 1 LASTPIN (-4000 2200) $PN 2
J 0
(-4038 2212);
DISPLAY 0.787234 (-4038 2212);
PAINT MONO (-4038 2212);
FORCEPROP 1 LAST MATERIAL CHIP
J 0
(-4100 2050);
DISPLAY 0.978723 (-4100 2050);
FORCEPROP 1 LAST TOLERANCE 5%
J 0
(-4100 2100);
DISPLAY 0.978723 (-4100 2100);
FORCEPROP 1 LAST WATTAGE 1/4W
J 2
(-4125 2050);
DISPLAY 0.978723 (-4125 2050);
FORCEPROP 1 LAST VALUE 0
J 2
(-4125 2100);
DISPLAY 0.978723 (-4125 2100);
FORCEPROP 1 LAST PACK_TYPE 0603LF
J 0
(-3850 2050);
DISPLAY 0.978723 (-3850 2050);
FORCEPROP 2 LAST CDS_LIB pure_quanta
J 0
(-4100 2200);
DISPLAY INVISIBLE (-4100 2200);
FORCEPROP 1 LAST PATH I36
J 0
(-4150 2350);
DISPLAY 0.978723 (-4150 2350);
PAINT WHITE (-4150 2350);
DISPLAY INVISIBLE (-4150 2350);
FORCEPROP 1 LAST PART_NUMBER CS00006J900
J 0
(-4325 1975);
DISPLAY 0.978723 (-4325 1975);
DISPLAY INVISIBLE (-4325 1975);
FORCEADD Q_CAP..1
(-3375 1950);
FORCEPROP 1 LAST LOCATION C662
J 0
(-3325 2050);
DISPLAY 0.978723 (-3325 2050);
PAINT WHITE (-3325 2050);
FORCEPROP 0 LAST $SEC 1
J 0
(-3325 2100);
DISPLAY 0.680851 (-3325 2100);
PAINT MONO (-3325 2100);
DISPLAY INVISIBLE (-3325 2100);
FORCEPROP 0 LAST CDS_SEC 1
J 0
(-3325 2100);
DISPLAY 0.680851 (-3325 2100);
DISPLAY INVISIBLE (-3325 2100);
FORCEPROP 1 LASTPIN (-3375 2050) $PN 1
J 0
(-3365 2030);
DISPLAY 0.787234 (-3365 2030);
PAINT MONO (-3365 2030);
FORCEPROP 1 LASTPIN (-3375 1850) $PN 2
J 0
(-3365 1830);
DISPLAY 0.787234 (-3365 1830);
PAINT MONO (-3365 1830);
FORCEPROP 1 LAST PACK_TYPE C0201
J 0
(-3325 1800);
DISPLAY 0.638298 (-3325 1800);
FORCEPROP 1 LAST MATERIAL X7S
J 0
(-3325 1850);
DISPLAY 0.638298 (-3325 1850);
FORCEPROP 1 LAST TOLERANCE 10%
J 0
(-3325 1900);
DISPLAY 0.638298 (-3325 1900);
FORCEPROP 1 LAST VOLTAGE 10V
J 0
(-3325 1950);
DISPLAY 0.638298 (-3325 1950);
FORCEPROP 1 LAST VALUE 0.1UF
J 0
(-3325 2000);
DISPLAY 0.638298 (-3325 2000);
FORCEPROP 2 LAST CDS_LIB pure_quanta
J 0
(-3375 1950);
DISPLAY INVISIBLE (-3375 1950);
FORCEPROP 1 LAST PATH I37
J 0
(-3325 2100);
DISPLAY 0.978723 (-3325 2100);
PAINT WHITE (-3325 2100);
DISPLAY INVISIBLE (-3325 2100);
FORCEPROP 1 LAST PART_NUMBER CH4102K6E00
J 0
(-3325 1800);
DISPLAY 0.978723 (-3325 1800);
DISPLAY INVISIBLE (-3325 1800);
FORCEADD Q_CAP..1
(-3650 2650);
FORCEPROP 1 LAST LOCATION C609
J 0
(-3600 2750);
DISPLAY 0.978723 (-3600 2750);
PAINT WHITE (-3600 2750);
FORCEPROP 0 LAST $SEC 1
J 0
(-3600 2800);
DISPLAY 0.680851 (-3600 2800);
PAINT MONO (-3600 2800);
DISPLAY INVISIBLE (-3600 2800);
FORCEPROP 0 LAST CDS_SEC 1
J 0
(-3600 2800);
DISPLAY 0.680851 (-3600 2800);
DISPLAY INVISIBLE (-3600 2800);
FORCEPROP 1 LASTPIN (-3650 2750) $PN 1
J 0
(-3640 2730);
DISPLAY 0.787234 (-3640 2730);
PAINT MONO (-3640 2730);
FORCEPROP 1 LASTPIN (-3650 2550) $PN 2
J 0
(-3640 2530);
DISPLAY 0.787234 (-3640 2530);
PAINT MONO (-3640 2530);
FORCEPROP 1 LAST PACK_TYPE 0201
J 0
(-3600 2500);
DISPLAY 0.510638 (-3600 2500);
FORCEPROP 1 LAST VALUE 1UF
J 0
(-3600 2700);
DISPLAY 0.510638 (-3600 2700);
FORCEPROP 1 LAST MATERIAL X6S
J 0
(-3600 2550);
DISPLAY 0.510638 (-3600 2550);
FORCEPROP 1 LAST TOLERANCE 20%
J 0
(-3600 2600);
DISPLAY 0.510638 (-3600 2600);
FORCEPROP 1 LAST VOLTAGE 4V
J 0
(-3600 2650);
DISPLAY 0.510638 (-3600 2650);
FORCEPROP 2 LAST CDS_LIB pure_quanta
J 0
(-3650 2650);
DISPLAY INVISIBLE (-3650 2650);
FORCEPROP 1 LAST PATH I38
J 0
(-3600 2800);
DISPLAY 0.978723 (-3600 2800);
PAINT WHITE (-3600 2800);
DISPLAY INVISIBLE (-3600 2800);
FORCEPROP 1 LAST PART_NUMBER CH-10KMEE00
J 0
(-3600 2500);
DISPLAY 0.510638 (-3600 2500);
DISPLAY INVISIBLE (-3600 2500);
FORCEADD Q_CAP..1
(-3425 2650);
FORCEPROP 1 LAST LOCATION C618
J 0
(-3375 2750);
DISPLAY 0.978723 (-3375 2750);
PAINT WHITE (-3375 2750);
FORCEPROP 0 LAST $SEC 1
J 0
(-3375 2800);
DISPLAY 0.680851 (-3375 2800);
PAINT MONO (-3375 2800);
DISPLAY INVISIBLE (-3375 2800);
FORCEPROP 0 LAST CDS_SEC 1
J 0
(-3375 2800);
DISPLAY 0.680851 (-3375 2800);
DISPLAY INVISIBLE (-3375 2800);
FORCEPROP 1 LASTPIN (-3425 2750) $PN 1
J 0
(-3415 2730);
DISPLAY 0.787234 (-3415 2730);
PAINT MONO (-3415 2730);
FORCEPROP 1 LASTPIN (-3425 2550) $PN 2
J 0
(-3415 2530);
DISPLAY 0.787234 (-3415 2530);
PAINT MONO (-3415 2530);
FORCEPROP 1 LAST PACK_TYPE 0201
J 0
(-3375 2500);
DISPLAY 0.510638 (-3375 2500);
FORCEPROP 1 LAST VOLTAGE 4V
J 0
(-3375 2650);
DISPLAY 0.510638 (-3375 2650);
FORCEPROP 1 LAST VALUE 1UF
J 0
(-3375 2700);
DISPLAY 0.510638 (-3375 2700);
FORCEPROP 1 LAST MATERIAL X6S
J 0
(-3375 2550);
DISPLAY 0.510638 (-3375 2550);
FORCEPROP 1 LAST TOLERANCE 20%
J 0
(-3375 2600);
DISPLAY 0.510638 (-3375 2600);
FORCEPROP 2 LAST CDS_LIB pure_quanta
J 0
(-3425 2650);
DISPLAY INVISIBLE (-3425 2650);
FORCEPROP 1 LAST PATH I39
J 0
(-3375 2800);
DISPLAY 0.978723 (-3375 2800);
PAINT WHITE (-3375 2800);
DISPLAY INVISIBLE (-3375 2800);
FORCEPROP 1 LAST PART_NUMBER CH-10KMEE00
J 0
(-3375 2500);
DISPLAY 0.510638 (-3375 2500);
DISPLAY INVISIBLE (-3375 2500);
FORCEADD Q_RES..1
(-7875 3475);
FORCEPROP 1 LAST LOCATION R1002
J 0
(-8150 3500);
DISPLAY 0.808511 (-8150 3500);
FORCEPROP 2 LAST SEC 1
J 0
(-7925 3675);
DISPLAY 0.680851 (-7925 3675);
PAINT MONO (-7925 3675);
DISPLAY INVISIBLE (-7925 3675);
FORCEPROP 1 LASTPIN (-7975 3475) $PN 1
J 0
(-7963 3487);
DISPLAY 0.787234 (-7963 3487);
PAINT MONO (-7963 3487);
FORCEPROP 1 LASTPIN (-7775 3475) $PN 2
J 0
(-7813 3487);
DISPLAY 0.787234 (-7813 3487);
PAINT MONO (-7813 3487);
FORCEPROP 1 LAST PACK_TYPE 0402LF
J 0
(-8025 3425);
DISPLAY 0.638298 (-8025 3425);
FORCEPROP 1 LAST TOLERANCE 5%
J 0
(-7825 3425);
DISPLAY 0.638298 (-7825 3425);
FORCEPROP 1 LAST VALUE 0
J 2
(-7725 3500);
DISPLAY 0.638298 (-7725 3500);
FORCEPROP 1 LAST MATERIAL EMPTY
J 0
(-7850 3375);
DISPLAY 0.638298 (-7850 3375);
FORCEPROP 1 LAST WATTAGE 1/16W
J 2
(-7875 3375);
DISPLAY 0.638298 (-7875 3375);
FORCEPROP 2 LAST CDS_LIB pure_quanta
J 0
(-7875 3475);
DISPLAY INVISIBLE (-7875 3475);
FORCEPROP 2 LAST SEC_TYPE 0402LF
J 0
(-7925 3675);
DISPLAY 0.680851 (-7925 3675);
DISPLAY INVISIBLE (-7925 3675);
FORCEPROP 1 LAST PATH I4
J 0
(-7925 3625);
DISPLAY 0.978723 (-7925 3625);
PAINT WHITE (-7925 3625);
DISPLAY INVISIBLE (-7925 3625);
FORCEPROP 1 LAST PART_NUMBER CS00002JB13
J 0
(-7925 3575);
DISPLAY 0.978723 (-7925 3575);
DISPLAY INVISIBLE (-7925 3575);
FORCEADD Q_CAP..1
(-3650 3275);
FORCEPROP 1 LAST LOCATION C626
J 0
(-3600 3375);
DISPLAY 0.978723 (-3600 3375);
PAINT WHITE (-3600 3375);
FORCEPROP 0 LAST $SEC 1
J 0
(-3600 3425);
DISPLAY 0.680851 (-3600 3425);
PAINT MONO (-3600 3425);
DISPLAY INVISIBLE (-3600 3425);
FORCEPROP 0 LAST CDS_SEC 1
J 0
(-3600 3425);
DISPLAY 0.680851 (-3600 3425);
DISPLAY INVISIBLE (-3600 3425);
FORCEPROP 1 LASTPIN (-3650 3375) $PN 1
J 0
(-3640 3355);
DISPLAY 0.787234 (-3640 3355);
PAINT MONO (-3640 3355);
FORCEPROP 1 LASTPIN (-3650 3175) $PN 2
J 0
(-3640 3155);
DISPLAY 0.787234 (-3640 3155);
PAINT MONO (-3640 3155);
FORCEPROP 1 LAST VOLTAGE 6.3V
J 0
(-3600 3275);
DISPLAY 0.510638 (-3600 3275);
FORCEPROP 1 LAST VALUE 10UF
J 0
(-3600 3325);
DISPLAY 0.510638 (-3600 3325);
FORCEPROP 1 LAST PACK_TYPE C0402
J 0
(-3600 3125);
DISPLAY 0.510638 (-3600 3125);
FORCEPROP 1 LAST TOLERANCE 20%
J 0
(-3600 3225);
DISPLAY 0.510638 (-3600 3225);
FORCEPROP 1 LAST MATERIAL X6S
J 0
(-3600 3175);
DISPLAY 0.510638 (-3600 3175);
FORCEPROP 2 LAST CDS_LIB pure_quanta
J 0
(-3650 3275);
DISPLAY INVISIBLE (-3650 3275);
FORCEPROP 1 LAST PATH I40
J 0
(-3600 3425);
DISPLAY 0.978723 (-3600 3425);
PAINT WHITE (-3600 3425);
DISPLAY INVISIBLE (-3600 3425);
FORCEPROP 1 LAST PART_NUMBER CH6101MEB01
J 0
(-3600 3125);
DISPLAY 0.978723 (-3600 3125);
DISPLAY INVISIBLE (-3600 3125);
FORCEADD Q_CAP..1
(-3425 3275);
FORCEPROP 1 LAST LOCATION C645
J 0
(-3375 3375);
DISPLAY 0.978723 (-3375 3375);
PAINT WHITE (-3375 3375);
FORCEPROP 0 LAST $SEC 1
J 0
(-3375 3425);
DISPLAY 0.680851 (-3375 3425);
PAINT MONO (-3375 3425);
DISPLAY INVISIBLE (-3375 3425);
FORCEPROP 0 LAST CDS_SEC 1
J 0
(-3375 3425);
DISPLAY 0.680851 (-3375 3425);
DISPLAY INVISIBLE (-3375 3425);
FORCEPROP 1 LASTPIN (-3425 3375) $PN 1
J 0
(-3415 3355);
DISPLAY 0.787234 (-3415 3355);
PAINT MONO (-3415 3355);
FORCEPROP 1 LASTPIN (-3425 3175) $PN 2
J 0
(-3415 3155);
DISPLAY 0.787234 (-3415 3155);
PAINT MONO (-3415 3155);
FORCEPROP 1 LAST TOLERANCE 20%
J 0
(-3375 3225);
DISPLAY 0.510638 (-3375 3225);
FORCEPROP 1 LAST VOLTAGE 6.3V
J 0
(-3375 3275);
DISPLAY 0.510638 (-3375 3275);
FORCEPROP 1 LAST MATERIAL X6S
J 0
(-3375 3175);
DISPLAY 0.510638 (-3375 3175);
FORCEPROP 1 LAST PACK_TYPE C0402
J 0
(-3375 3125);
DISPLAY 0.510638 (-3375 3125);
FORCEPROP 1 LAST VALUE 10UF
J 0
(-3375 3325);
DISPLAY 0.510638 (-3375 3325);
FORCEPROP 2 LAST CDS_LIB pure_quanta
J 0
(-3425 3275);
DISPLAY INVISIBLE (-3425 3275);
FORCEPROP 1 LAST PATH I41
J 0
(-3375 3425);
DISPLAY 0.978723 (-3375 3425);
PAINT WHITE (-3375 3425);
DISPLAY INVISIBLE (-3375 3425);
FORCEPROP 1 LAST PART_NUMBER CH6101MEB01
J 0
(-3375 3125);
DISPLAY 0.978723 (-3375 3125);
DISPLAY INVISIBLE (-3375 3125);
FORCEADD Q_CAP..1
(-3075 1950);
FORCEPROP 1 LAST LOCATION C616
J 0
(-3025 2050);
DISPLAY 0.978723 (-3025 2050);
PAINT WHITE (-3025 2050);
FORCEPROP 0 LAST $SEC 1
J 0
(-3025 2100);
DISPLAY 0.680851 (-3025 2100);
PAINT MONO (-3025 2100);
DISPLAY INVISIBLE (-3025 2100);
FORCEPROP 0 LAST CDS_SEC 1
J 0
(-3025 2100);
DISPLAY 0.680851 (-3025 2100);
DISPLAY INVISIBLE (-3025 2100);
FORCEPROP 1 LASTPIN (-3075 2050) $PN 1
J 0
(-3065 2030);
DISPLAY 0.787234 (-3065 2030);
PAINT MONO (-3065 2030);
FORCEPROP 1 LASTPIN (-3075 1850) $PN 2
J 0
(-3065 1830);
DISPLAY 0.787234 (-3065 1830);
PAINT MONO (-3065 1830);
FORCEPROP 1 LAST PACK_TYPE C0201
J 0
(-3025 1800);
DISPLAY 0.638298 (-3025 1800);
FORCEPROP 1 LAST MATERIAL X7S
J 0
(-3025 1850);
DISPLAY 0.638298 (-3025 1850);
FORCEPROP 1 LAST TOLERANCE 10%
J 0
(-3025 1900);
DISPLAY 0.638298 (-3025 1900);
FORCEPROP 1 LAST VOLTAGE 10V
J 0
(-3025 1950);
DISPLAY 0.638298 (-3025 1950);
FORCEPROP 1 LAST VALUE 0.1UF
J 0
(-3025 2000);
DISPLAY 0.638298 (-3025 2000);
FORCEPROP 2 LAST CDS_LIB pure_quanta
J 0
(-3075 1950);
DISPLAY INVISIBLE (-3075 1950);
FORCEPROP 1 LAST PATH I42
J 0
(-3025 2100);
DISPLAY 0.978723 (-3025 2100);
PAINT WHITE (-3025 2100);
DISPLAY INVISIBLE (-3025 2100);
FORCEPROP 1 LAST PART_NUMBER CH4102K6E00
J 0
(-3025 1800);
DISPLAY 0.978723 (-3025 1800);
DISPLAY INVISIBLE (-3025 1800);
FORCEADD Q_CAP..1
(-2850 1950);
FORCEPROP 1 LAST LOCATION C657
J 0
(-2800 2050);
DISPLAY 0.978723 (-2800 2050);
PAINT WHITE (-2800 2050);
FORCEPROP 0 LAST $SEC 1
J 0
(-2800 2100);
DISPLAY 0.680851 (-2800 2100);
PAINT MONO (-2800 2100);
DISPLAY INVISIBLE (-2800 2100);
FORCEPROP 0 LAST CDS_SEC 1
J 0
(-2800 2100);
DISPLAY 0.680851 (-2800 2100);
DISPLAY INVISIBLE (-2800 2100);
FORCEPROP 1 LASTPIN (-2850 2050) $PN 1
J 0
(-2840 2030);
DISPLAY 0.787234 (-2840 2030);
PAINT MONO (-2840 2030);
FORCEPROP 1 LASTPIN (-2850 1850) $PN 2
J 0
(-2840 1830);
DISPLAY 0.787234 (-2840 1830);
PAINT MONO (-2840 1830);
FORCEPROP 1 LAST VALUE 0.1UF
J 0
(-2800 2000);
DISPLAY 0.638298 (-2800 2000);
FORCEPROP 1 LAST VOLTAGE 10V
J 0
(-2800 1950);
DISPLAY 0.638298 (-2800 1950);
FORCEPROP 1 LAST TOLERANCE 10%
J 0
(-2800 1900);
DISPLAY 0.638298 (-2800 1900);
FORCEPROP 1 LAST MATERIAL X7S
J 0
(-2800 1850);
DISPLAY 0.638298 (-2800 1850);
FORCEPROP 1 LAST PACK_TYPE C0201
J 0
(-2800 1800);
DISPLAY 0.638298 (-2800 1800);
FORCEPROP 2 LAST CDS_LIB pure_quanta
J 0
(-2850 1950);
DISPLAY INVISIBLE (-2850 1950);
FORCEPROP 1 LAST PATH I43
J 0
(-2800 2100);
DISPLAY 0.978723 (-2800 2100);
PAINT WHITE (-2800 2100);
DISPLAY INVISIBLE (-2800 2100);
FORCEPROP 1 LAST PART_NUMBER CH4102K6E00
J 0
(-2800 1800);
DISPLAY 0.978723 (-2800 1800);
DISPLAY INVISIBLE (-2800 1800);
FORCEADD Q_CAP..1
(-3175 2650);
FORCEPROP 1 LAST LOCATION C607
J 0
(-3125 2750);
DISPLAY 0.978723 (-3125 2750);
PAINT WHITE (-3125 2750);
FORCEPROP 0 LAST $SEC 1
J 0
(-3125 2800);
DISPLAY 0.680851 (-3125 2800);
PAINT MONO (-3125 2800);
DISPLAY INVISIBLE (-3125 2800);
FORCEPROP 0 LAST CDS_SEC 1
J 0
(-3125 2800);
DISPLAY 0.680851 (-3125 2800);
DISPLAY INVISIBLE (-3125 2800);
FORCEPROP 1 LASTPIN (-3175 2750) $PN 1
J 0
(-3165 2730);
DISPLAY 0.787234 (-3165 2730);
PAINT MONO (-3165 2730);
FORCEPROP 1 LASTPIN (-3175 2550) $PN 2
J 0
(-3165 2530);
DISPLAY 0.787234 (-3165 2530);
PAINT MONO (-3165 2530);
FORCEPROP 1 LAST MATERIAL X6S
J 0
(-3125 2550);
DISPLAY 0.510638 (-3125 2550);
FORCEPROP 1 LAST VALUE 1UF
J 0
(-3125 2700);
DISPLAY 0.510638 (-3125 2700);
FORCEPROP 1 LAST PACK_TYPE 0201
J 0
(-3125 2500);
DISPLAY 0.510638 (-3125 2500);
FORCEPROP 1 LAST TOLERANCE 20%
J 0
(-3125 2600);
DISPLAY 0.510638 (-3125 2600);
FORCEPROP 1 LAST VOLTAGE 4V
J 0
(-3125 2650);
DISPLAY 0.510638 (-3125 2650);
FORCEPROP 2 LAST CDS_LIB pure_quanta
J 0
(-3175 2650);
DISPLAY INVISIBLE (-3175 2650);
FORCEPROP 1 LAST PATH I44
J 0
(-3125 2800);
DISPLAY 0.978723 (-3125 2800);
PAINT WHITE (-3125 2800);
DISPLAY INVISIBLE (-3125 2800);
FORCEPROP 1 LAST PART_NUMBER CH-10KMEE00
J 0
(-3125 2500);
DISPLAY 0.510638 (-3125 2500);
DISPLAY INVISIBLE (-3125 2500);
FORCEADD Q_CAP..1
(-2950 2650);
FORCEPROP 1 LAST LOCATION C643
J 0
(-2900 2750);
DISPLAY 0.978723 (-2900 2750);
PAINT WHITE (-2900 2750);
FORCEPROP 0 LAST $SEC 1
J 0
(-2900 2800);
DISPLAY 0.680851 (-2900 2800);
PAINT MONO (-2900 2800);
DISPLAY INVISIBLE (-2900 2800);
FORCEPROP 0 LAST CDS_SEC 1
J 0
(-2900 2800);
DISPLAY 0.680851 (-2900 2800);
DISPLAY INVISIBLE (-2900 2800);
FORCEPROP 1 LASTPIN (-2950 2750) $PN 1
J 0
(-2940 2730);
DISPLAY 0.787234 (-2940 2730);
PAINT MONO (-2940 2730);
FORCEPROP 1 LASTPIN (-2950 2550) $PN 2
J 0
(-2940 2530);
DISPLAY 0.787234 (-2940 2530);
PAINT MONO (-2940 2530);
FORCEPROP 1 LAST VALUE 1UF
J 0
(-2900 2700);
DISPLAY 0.510638 (-2900 2700);
FORCEPROP 1 LAST VOLTAGE 4V
J 0
(-2900 2650);
DISPLAY 0.510638 (-2900 2650);
FORCEPROP 1 LAST TOLERANCE 20%
J 0
(-2900 2600);
DISPLAY 0.510638 (-2900 2600);
FORCEPROP 1 LAST PACK_TYPE 0201
J 0
(-2900 2500);
DISPLAY 0.510638 (-2900 2500);
FORCEPROP 1 LAST MATERIAL X6S
J 0
(-2900 2550);
DISPLAY 0.510638 (-2900 2550);
FORCEPROP 2 LAST CDS_LIB pure_quanta
J 0
(-2950 2650);
DISPLAY INVISIBLE (-2950 2650);
FORCEPROP 1 LAST PATH I45
J 0
(-2900 2800);
DISPLAY 0.978723 (-2900 2800);
PAINT WHITE (-2900 2800);
DISPLAY INVISIBLE (-2900 2800);
FORCEPROP 1 LAST PART_NUMBER CH-10KMEE00
J 0
(-2900 2500);
DISPLAY 0.510638 (-2900 2500);
DISPLAY INVISIBLE (-2900 2500);
FORCEADD Q_CAP..1
(-2600 1950);
FORCEPROP 1 LAST LOCATION C635
J 0
(-2550 2050);
DISPLAY 0.978723 (-2550 2050);
PAINT WHITE (-2550 2050);
FORCEPROP 0 LAST $SEC 1
J 0
(-2550 2100);
DISPLAY 0.680851 (-2550 2100);
PAINT MONO (-2550 2100);
DISPLAY INVISIBLE (-2550 2100);
FORCEPROP 0 LAST CDS_SEC 1
J 0
(-2550 2100);
DISPLAY 0.680851 (-2550 2100);
DISPLAY INVISIBLE (-2550 2100);
FORCEPROP 1 LASTPIN (-2600 2050) $PN 1
J 0
(-2590 2030);
DISPLAY 0.787234 (-2590 2030);
PAINT MONO (-2590 2030);
FORCEPROP 1 LASTPIN (-2600 1850) $PN 2
J 0
(-2590 1830);
DISPLAY 0.787234 (-2590 1830);
PAINT MONO (-2590 1830);
FORCEPROP 1 LAST MATERIAL X7S
J 0
(-2550 1850);
DISPLAY 0.638298 (-2550 1850);
FORCEPROP 1 LAST TOLERANCE 10%
J 0
(-2550 1900);
DISPLAY 0.638298 (-2550 1900);
FORCEPROP 1 LAST VOLTAGE 10V
J 0
(-2550 1950);
DISPLAY 0.638298 (-2550 1950);
FORCEPROP 1 LAST PACK_TYPE C0201
J 0
(-2550 1800);
DISPLAY 0.638298 (-2550 1800);
FORCEPROP 1 LAST VALUE 0.1UF
J 0
(-2550 2000);
DISPLAY 0.638298 (-2550 2000);
FORCEPROP 2 LAST CDS_LIB pure_quanta
J 0
(-2600 1950);
DISPLAY INVISIBLE (-2600 1950);
FORCEPROP 1 LAST PATH I46
J 0
(-2550 2100);
DISPLAY 0.978723 (-2550 2100);
PAINT WHITE (-2550 2100);
DISPLAY INVISIBLE (-2550 2100);
FORCEPROP 1 LAST PART_NUMBER CH4102K6E00
J 0
(-2550 1800);
DISPLAY 0.978723 (-2550 1800);
DISPLAY INVISIBLE (-2550 1800);
FORCEADD Q_CAP..1
(-2350 1950);
FORCEPROP 1 LAST LOCATION C627
J 0
(-2300 2050);
DISPLAY 0.978723 (-2300 2050);
PAINT WHITE (-2300 2050);
FORCEPROP 0 LAST $SEC 1
J 0
(-2300 2100);
DISPLAY 0.680851 (-2300 2100);
PAINT MONO (-2300 2100);
DISPLAY INVISIBLE (-2300 2100);
FORCEPROP 0 LAST CDS_SEC 1
J 0
(-2300 2100);
DISPLAY 0.680851 (-2300 2100);
DISPLAY INVISIBLE (-2300 2100);
FORCEPROP 1 LASTPIN (-2350 2050) $PN 1
J 0
(-2340 2030);
DISPLAY 0.787234 (-2340 2030);
PAINT MONO (-2340 2030);
FORCEPROP 1 LASTPIN (-2350 1850) $PN 2
J 0
(-2340 1830);
DISPLAY 0.787234 (-2340 1830);
PAINT MONO (-2340 1830);
FORCEPROP 1 LAST VALUE 0.1UF
J 0
(-2300 2000);
DISPLAY 0.638298 (-2300 2000);
FORCEPROP 1 LAST PACK_TYPE C0201
J 0
(-2300 1800);
DISPLAY 0.638298 (-2300 1800);
FORCEPROP 1 LAST TOLERANCE 10%
J 0
(-2300 1900);
DISPLAY 0.638298 (-2300 1900);
FORCEPROP 1 LAST MATERIAL X7S
J 0
(-2300 1850);
DISPLAY 0.638298 (-2300 1850);
FORCEPROP 1 LAST VOLTAGE 10V
J 0
(-2300 1950);
DISPLAY 0.638298 (-2300 1950);
FORCEPROP 2 LAST CDS_LIB pure_quanta
J 0
(-2350 1950);
DISPLAY INVISIBLE (-2350 1950);
FORCEPROP 1 LAST PATH I47
J 0
(-2300 2100);
DISPLAY 0.978723 (-2300 2100);
PAINT WHITE (-2300 2100);
DISPLAY INVISIBLE (-2300 2100);
FORCEPROP 1 LAST PART_NUMBER CH4102K6E00
J 0
(-2300 1800);
DISPLAY 0.978723 (-2300 1800);
DISPLAY INVISIBLE (-2300 1800);
FORCEADD Q_CAP..1
(-2700 2650);
FORCEPROP 1 LAST LOCATION C647
J 0
(-2650 2750);
DISPLAY 0.978723 (-2650 2750);
PAINT WHITE (-2650 2750);
FORCEPROP 0 LAST $SEC 1
J 0
(-2650 2800);
DISPLAY 0.680851 (-2650 2800);
PAINT MONO (-2650 2800);
DISPLAY INVISIBLE (-2650 2800);
FORCEPROP 0 LAST CDS_SEC 1
J 0
(-2650 2800);
DISPLAY 0.680851 (-2650 2800);
DISPLAY INVISIBLE (-2650 2800);
FORCEPROP 1 LASTPIN (-2700 2750) $PN 1
J 0
(-2690 2730);
DISPLAY 0.787234 (-2690 2730);
PAINT MONO (-2690 2730);
FORCEPROP 1 LASTPIN (-2700 2550) $PN 2
J 0
(-2690 2530);
DISPLAY 0.787234 (-2690 2530);
PAINT MONO (-2690 2530);
FORCEPROP 1 LAST VOLTAGE 4V
J 0
(-2650 2650);
DISPLAY 0.510638 (-2650 2650);
FORCEPROP 1 LAST PACK_TYPE 0201
J 0
(-2650 2500);
DISPLAY 0.510638 (-2650 2500);
FORCEPROP 1 LAST VALUE 1UF
J 0
(-2650 2700);
DISPLAY 0.510638 (-2650 2700);
FORCEPROP 1 LAST MATERIAL X6S
J 0
(-2650 2550);
DISPLAY 0.510638 (-2650 2550);
FORCEPROP 1 LAST TOLERANCE 20%
J 0
(-2650 2600);
DISPLAY 0.510638 (-2650 2600);
FORCEPROP 2 LAST CDS_LIB pure_quanta
J 0
(-2700 2650);
DISPLAY INVISIBLE (-2700 2650);
FORCEPROP 1 LAST PATH I48
J 0
(-2650 2800);
DISPLAY 0.978723 (-2650 2800);
PAINT WHITE (-2650 2800);
DISPLAY INVISIBLE (-2650 2800);
FORCEPROP 1 LAST PART_NUMBER CH-10KMEE00
J 0
(-2650 2500);
DISPLAY 0.510638 (-2650 2500);
DISPLAY INVISIBLE (-2650 2500);
FORCEADD Q_CAP..1
(-2250 2625);
FORCEPROP 1 LAST LOCATION C654
J 0
(-2200 2725);
DISPLAY 0.978723 (-2200 2725);
PAINT WHITE (-2200 2725);
FORCEPROP 0 LAST $SEC 1
J 0
(-2200 2775);
DISPLAY 0.680851 (-2200 2775);
PAINT MONO (-2200 2775);
DISPLAY INVISIBLE (-2200 2775);
FORCEPROP 0 LAST CDS_SEC 1
J 0
(-2200 2775);
DISPLAY 0.680851 (-2200 2775);
DISPLAY INVISIBLE (-2200 2775);
FORCEPROP 1 LASTPIN (-2250 2725) $PN 1
J 0
(-2240 2705);
DISPLAY 0.787234 (-2240 2705);
PAINT MONO (-2240 2705);
FORCEPROP 1 LASTPIN (-2250 2525) $PN 2
J 0
(-2240 2505);
DISPLAY 0.787234 (-2240 2505);
PAINT MONO (-2240 2505);
FORCEPROP 1 LAST TOLERANCE 20%
J 0
(-2200 2575);
DISPLAY 0.510638 (-2200 2575);
FORCEPROP 1 LAST MATERIAL X6S
J 0
(-2200 2525);
DISPLAY 0.510638 (-2200 2525);
FORCEPROP 1 LAST VOLTAGE 4V
J 0
(-2200 2625);
DISPLAY 0.510638 (-2200 2625);
FORCEPROP 1 LAST VALUE 1UF
J 0
(-2200 2675);
DISPLAY 0.510638 (-2200 2675);
FORCEPROP 1 LAST PACK_TYPE 0201
J 0
(-2200 2475);
DISPLAY 0.510638 (-2200 2475);
FORCEPROP 2 LAST CDS_LIB pure_quanta
J 0
(-2250 2625);
DISPLAY INVISIBLE (-2250 2625);
FORCEPROP 1 LAST PATH I49
J 0
(-2200 2775);
DISPLAY 0.978723 (-2200 2775);
PAINT WHITE (-2200 2775);
DISPLAY INVISIBLE (-2200 2775);
FORCEPROP 1 LAST PART_NUMBER CH-10KMEE00
J 0
(-2200 2475);
DISPLAY 0.510638 (-2200 2475);
DISPLAY INVISIBLE (-2200 2475);
FORCEADD Q_CAP..1
(-6950 2825);
FORCEPROP 1 LAST LOCATION C598
J 0
(-6900 2925);
DISPLAY 0.638298 (-6900 2925);
PAINT WHITE (-6900 2925);
FORCEPROP 0 LAST $SEC 1
J 0
(-6900 2975);
DISPLAY 0.680851 (-6900 2975);
PAINT MONO (-6900 2975);
DISPLAY INVISIBLE (-6900 2975);
FORCEPROP 0 LAST CDS_SEC 1
J 0
(-6900 2975);
DISPLAY 0.680851 (-6900 2975);
DISPLAY INVISIBLE (-6900 2975);
FORCEPROP 1 LASTPIN (-6950 2925) $PN 1
J 0
(-6940 2905);
DISPLAY 0.787234 (-6940 2905);
PAINT MONO (-6940 2905);
FORCEPROP 1 LASTPIN (-6950 2725) $PN 2
J 0
(-6940 2705);
DISPLAY 0.787234 (-6940 2705);
PAINT MONO (-6940 2705);
FORCEPROP 1 LAST MATERIAL X6S
J 0
(-6900 2725);
DISPLAY 0.510638 (-6900 2725);
FORCEPROP 1 LAST PACK_TYPE 0201
J 0
(-6900 2675);
DISPLAY 0.510638 (-6900 2675);
FORCEPROP 1 LAST VALUE 1UF
J 0
(-6900 2875);
DISPLAY 0.510638 (-6900 2875);
FORCEPROP 1 LAST VOLTAGE 4V
J 0
(-6900 2825);
DISPLAY 0.510638 (-6900 2825);
FORCEPROP 1 LAST TOLERANCE 20%
J 0
(-6900 2775);
DISPLAY 0.510638 (-6900 2775);
FORCEPROP 2 LAST CDS_LIB pure_quanta
J 0
(-6950 2825);
DISPLAY INVISIBLE (-6950 2825);
FORCEPROP 1 LAST PATH I5
J 0
(-6900 2975);
DISPLAY 0.978723 (-6900 2975);
PAINT WHITE (-6900 2975);
DISPLAY INVISIBLE (-6900 2975);
FORCEPROP 1 LAST PART_NUMBER CH-10KMEE00
J 0
(-6900 2675);
DISPLAY 0.510638 (-6900 2675);
DISPLAY INVISIBLE (-6900 2675);
FORCEADD Q_CAP..1
(-3200 3275);
FORCEPROP 1 LAST LOCATION C644
J 0
(-3150 3375);
DISPLAY 0.978723 (-3150 3375);
PAINT WHITE (-3150 3375);
FORCEPROP 0 LAST $SEC 1
J 0
(-3150 3425);
DISPLAY 0.680851 (-3150 3425);
PAINT MONO (-3150 3425);
DISPLAY INVISIBLE (-3150 3425);
FORCEPROP 0 LAST CDS_SEC 1
J 0
(-3150 3425);
DISPLAY 0.680851 (-3150 3425);
DISPLAY INVISIBLE (-3150 3425);
FORCEPROP 1 LASTPIN (-3200 3375) $PN 1
J 0
(-3190 3355);
DISPLAY 0.787234 (-3190 3355);
PAINT MONO (-3190 3355);
FORCEPROP 1 LASTPIN (-3200 3175) $PN 2
J 0
(-3190 3155);
DISPLAY 0.787234 (-3190 3155);
PAINT MONO (-3190 3155);
FORCEPROP 1 LAST MATERIAL X6S
J 0
(-3150 3175);
DISPLAY 0.510638 (-3150 3175);
FORCEPROP 1 LAST VALUE 4.7UF
J 0
(-3150 3325);
DISPLAY 0.510638 (-3150 3325);
FORCEPROP 1 LAST TOLERANCE 20%
J 0
(-3150 3225);
DISPLAY 0.510638 (-3150 3225);
FORCEPROP 1 LAST PACK_TYPE 0402
J 0
(-3150 3125);
DISPLAY 0.510638 (-3150 3125);
FORCEPROP 1 LAST VOLTAGE 6.3V
J 0
(-3150 3275);
DISPLAY 0.510638 (-3150 3275);
FORCEPROP 2 LAST CDS_LIB pure_quanta
J 0
(-3200 3275);
DISPLAY INVISIBLE (-3200 3275);
FORCEPROP 1 LAST PATH I50
J 0
(-3150 3425);
DISPLAY 0.978723 (-3150 3425);
PAINT WHITE (-3150 3425);
DISPLAY INVISIBLE (-3150 3425);
FORCEPROP 1 LAST PART_NUMBER CH5471MEB01
J 0
(-3150 3125);
DISPLAY 0.978723 (-3150 3125);
DISPLAY INVISIBLE (-3150 3125);
FORCEADD Q_CAP..1
(-2975 3275);
FORCEPROP 1 LAST LOCATION C638
J 0
(-2925 3375);
DISPLAY 0.978723 (-2925 3375);
PAINT WHITE (-2925 3375);
FORCEPROP 0 LAST $SEC 1
J 0
(-2925 3425);
DISPLAY 0.680851 (-2925 3425);
PAINT MONO (-2925 3425);
DISPLAY INVISIBLE (-2925 3425);
FORCEPROP 0 LAST CDS_SEC 1
J 0
(-2925 3425);
DISPLAY 0.680851 (-2925 3425);
DISPLAY INVISIBLE (-2925 3425);
FORCEPROP 1 LASTPIN (-2975 3375) $PN 1
J 0
(-2965 3355);
DISPLAY 0.787234 (-2965 3355);
PAINT MONO (-2965 3355);
FORCEPROP 1 LASTPIN (-2975 3175) $PN 2
J 0
(-2965 3155);
DISPLAY 0.787234 (-2965 3155);
PAINT MONO (-2965 3155);
FORCEPROP 1 LAST PACK_TYPE 0402
J 0
(-2925 3125);
DISPLAY 0.510638 (-2925 3125);
FORCEPROP 1 LAST MATERIAL X6S
J 0
(-2925 3175);
DISPLAY 0.510638 (-2925 3175);
FORCEPROP 1 LAST TOLERANCE 20%
J 0
(-2925 3225);
DISPLAY 0.510638 (-2925 3225);
FORCEPROP 1 LAST VOLTAGE 6.3V
J 0
(-2925 3275);
DISPLAY 0.510638 (-2925 3275);
FORCEPROP 1 LAST VALUE 4.7UF
J 0
(-2925 3325);
DISPLAY 0.510638 (-2925 3325);
FORCEPROP 2 LAST CDS_LIB pure_quanta
J 0
(-2975 3275);
DISPLAY INVISIBLE (-2975 3275);
FORCEPROP 1 LAST PATH I51
J 0
(-2925 3425);
DISPLAY 0.978723 (-2925 3425);
PAINT WHITE (-2925 3425);
DISPLAY INVISIBLE (-2925 3425);
FORCEPROP 1 LAST PART_NUMBER CH5471MEB01
J 0
(-2925 3125);
DISPLAY 0.978723 (-2925 3125);
DISPLAY INVISIBLE (-2925 3125);
FORCEADD Q_CAP..1
(-2500 3275);
FORCEPROP 1 LAST LOCATION C649
J 0
(-2450 3375);
DISPLAY 0.978723 (-2450 3375);
PAINT WHITE (-2450 3375);
FORCEPROP 0 LAST $SEC 1
J 0
(-2450 3425);
DISPLAY 0.680851 (-2450 3425);
PAINT MONO (-2450 3425);
DISPLAY INVISIBLE (-2450 3425);
FORCEPROP 0 LAST CDS_SEC 1
J 0
(-2450 3425);
DISPLAY 0.680851 (-2450 3425);
DISPLAY INVISIBLE (-2450 3425);
FORCEPROP 1 LASTPIN (-2500 3375) $PN 1
J 0
(-2490 3355);
DISPLAY 0.787234 (-2490 3355);
PAINT MONO (-2490 3355);
FORCEPROP 1 LASTPIN (-2500 3175) $PN 2
J 0
(-2490 3155);
DISPLAY 0.787234 (-2490 3155);
PAINT MONO (-2490 3155);
FORCEPROP 1 LAST MATERIAL X6S
J 0
(-2450 3175);
DISPLAY 0.510638 (-2450 3175);
FORCEPROP 1 LAST VALUE 4.7UF
J 0
(-2450 3325);
DISPLAY 0.510638 (-2450 3325);
FORCEPROP 1 LAST TOLERANCE 20%
J 0
(-2450 3225);
DISPLAY 0.510638 (-2450 3225);
FORCEPROP 1 LAST VOLTAGE 6.3V
J 0
(-2450 3275);
DISPLAY 0.510638 (-2450 3275);
FORCEPROP 1 LAST PACK_TYPE 0402
J 0
(-2450 3125);
DISPLAY 0.510638 (-2450 3125);
FORCEPROP 2 LAST CDS_LIB pure_quanta
J 0
(-2500 3275);
DISPLAY INVISIBLE (-2500 3275);
FORCEPROP 1 LAST PATH I52
J 0
(-2450 3425);
DISPLAY 0.978723 (-2450 3425);
PAINT WHITE (-2450 3425);
DISPLAY INVISIBLE (-2450 3425);
FORCEPROP 1 LAST PART_NUMBER CH5471MEB01
J 0
(-2450 3125);
DISPLAY 0.978723 (-2450 3125);
DISPLAY INVISIBLE (-2450 3125);
FORCEADD Q_CAP..1
(-2275 3275);
FORCEPROP 1 LAST LOCATION C653
J 0
(-2225 3375);
DISPLAY 0.978723 (-2225 3375);
PAINT WHITE (-2225 3375);
FORCEPROP 0 LAST $SEC 1
J 0
(-2225 3425);
DISPLAY 0.680851 (-2225 3425);
PAINT MONO (-2225 3425);
DISPLAY INVISIBLE (-2225 3425);
FORCEPROP 0 LAST CDS_SEC 1
J 0
(-2225 3425);
DISPLAY 0.680851 (-2225 3425);
DISPLAY INVISIBLE (-2225 3425);
FORCEPROP 1 LASTPIN (-2275 3375) $PN 1
J 0
(-2265 3355);
DISPLAY 0.787234 (-2265 3355);
PAINT MONO (-2265 3355);
FORCEPROP 1 LASTPIN (-2275 3175) $PN 2
J 0
(-2265 3155);
DISPLAY 0.787234 (-2265 3155);
PAINT MONO (-2265 3155);
FORCEPROP 1 LAST VALUE 1UF
J 0
(-2225 3325);
DISPLAY 0.510638 (-2225 3325);
FORCEPROP 1 LAST MATERIAL X6S
J 0
(-2225 3175);
DISPLAY 0.510638 (-2225 3175);
FORCEPROP 1 LAST VOLTAGE 4V
J 0
(-2225 3275);
DISPLAY 0.510638 (-2225 3275);
FORCEPROP 1 LAST PACK_TYPE 0201
J 0
(-2225 3125);
DISPLAY 0.510638 (-2225 3125);
FORCEPROP 1 LAST TOLERANCE 20%
J 0
(-2225 3225);
DISPLAY 0.510638 (-2225 3225);
FORCEPROP 2 LAST CDS_LIB pure_quanta
J 0
(-2275 3275);
DISPLAY INVISIBLE (-2275 3275);
FORCEPROP 1 LAST PATH I53
J 0
(-2225 3425);
DISPLAY 0.978723 (-2225 3425);
PAINT WHITE (-2225 3425);
DISPLAY INVISIBLE (-2225 3425);
FORCEPROP 1 LAST PART_NUMBER CH-10KMEE00
J 0
(-2225 3125);
DISPLAY 0.510638 (-2225 3125);
DISPLAY INVISIBLE (-2225 3125);
FORCEADD UNIVERSAL_GND..1
(-1550 1525);
FORCEPROP 3 LASTPIN (-1550 1575) SIG_NAME GND\g
J 0
(-1540 1585);
DISPLAY 0.659574 (-1540 1585);
PAINT MONO (-1540 1585);
DISPLAY INVISIBLE (-1540 1585);
FORCEPROP 2 LAST CDS_LIB pure_quanta_power
J 0
(-1550 1525);
DISPLAY INVISIBLE (-1550 1525);
FORCEPROP 1 LAST HDL_POWER GND
J 1
(-1525 1450);
DISPLAY 0.872340 (-1525 1450);
PAINT GREEN (-1525 1450);
DISPLAY INVISIBLE (-1525 1450);
FORCEPROP 1 LAST PATH I54
J 0
(-1475 1525);
DISPLAY 0.872340 (-1475 1525);
PAINT AQUA (-1475 1525);
DISPLAY INVISIBLE (-1475 1525);
FORCEADD Q_CAP..1
(-1800 1950);
FORCEPROP 1 LAST LOCATION C631
J 0
(-1750 2050);
DISPLAY 0.978723 (-1750 2050);
PAINT WHITE (-1750 2050);
FORCEPROP 0 LAST $SEC 1
J 0
(-1750 2100);
DISPLAY 0.680851 (-1750 2100);
PAINT MONO (-1750 2100);
DISPLAY INVISIBLE (-1750 2100);
FORCEPROP 0 LAST CDS_SEC 1
J 0
(-1750 2100);
DISPLAY 0.680851 (-1750 2100);
DISPLAY INVISIBLE (-1750 2100);
FORCEPROP 1 LASTPIN (-1800 2050) $PN 1
J 0
(-1790 2030);
DISPLAY 0.787234 (-1790 2030);
PAINT MONO (-1790 2030);
FORCEPROP 1 LASTPIN (-1800 1850) $PN 2
J 0
(-1790 1830);
DISPLAY 0.787234 (-1790 1830);
PAINT MONO (-1790 1830);
FORCEPROP 1 LAST VALUE 0.1UF
J 0
(-1750 2000);
DISPLAY 0.638298 (-1750 2000);
FORCEPROP 1 LAST PACK_TYPE C0201
J 0
(-1750 1800);
DISPLAY 0.638298 (-1750 1800);
FORCEPROP 1 LAST TOLERANCE 10%
J 0
(-1750 1900);
DISPLAY 0.638298 (-1750 1900);
FORCEPROP 1 LAST MATERIAL X7S
J 0
(-1750 1850);
DISPLAY 0.638298 (-1750 1850);
FORCEPROP 1 LAST VOLTAGE 10V
J 0
(-1750 1950);
DISPLAY 0.638298 (-1750 1950);
FORCEPROP 2 LAST CDS_LIB pure_quanta
J 0
(-1800 1950);
DISPLAY INVISIBLE (-1800 1950);
FORCEPROP 1 LAST PATH I55
J 0
(-1750 2100);
DISPLAY 0.978723 (-1750 2100);
PAINT WHITE (-1750 2100);
DISPLAY INVISIBLE (-1750 2100);
FORCEPROP 1 LAST PART_NUMBER CH4102K6E00
J 0
(-1750 1800);
DISPLAY 0.978723 (-1750 1800);
DISPLAY INVISIBLE (-1750 1800);
FORCEADD Q_CAP..1
(-1550 1950);
FORCEPROP 1 LAST LOCATION C650
J 0
(-1500 2050);
DISPLAY 0.978723 (-1500 2050);
PAINT WHITE (-1500 2050);
FORCEPROP 0 LAST $SEC 1
J 0
(-1500 2100);
DISPLAY 0.680851 (-1500 2100);
PAINT MONO (-1500 2100);
DISPLAY INVISIBLE (-1500 2100);
FORCEPROP 0 LAST CDS_SEC 1
J 0
(-1500 2100);
DISPLAY 0.680851 (-1500 2100);
DISPLAY INVISIBLE (-1500 2100);
FORCEPROP 1 LASTPIN (-1550 2050) $PN 1
J 0
(-1540 2030);
DISPLAY 0.787234 (-1540 2030);
PAINT MONO (-1540 2030);
FORCEPROP 1 LASTPIN (-1550 1850) $PN 2
J 0
(-1540 1830);
DISPLAY 0.787234 (-1540 1830);
PAINT MONO (-1540 1830);
FORCEPROP 1 LAST PACK_TYPE C0201
J 0
(-1500 1800);
DISPLAY 0.638298 (-1500 1800);
FORCEPROP 1 LAST VALUE 0.1UF
J 0
(-1500 2000);
DISPLAY 0.638298 (-1500 2000);
FORCEPROP 1 LAST VOLTAGE 10V
J 0
(-1500 1950);
DISPLAY 0.638298 (-1500 1950);
FORCEPROP 1 LAST MATERIAL X7S
J 0
(-1500 1850);
DISPLAY 0.638298 (-1500 1850);
FORCEPROP 1 LAST TOLERANCE 10%
J 0
(-1500 1900);
DISPLAY 0.638298 (-1500 1900);
FORCEPROP 2 LAST CDS_LIB pure_quanta
J 0
(-1550 1950);
DISPLAY INVISIBLE (-1550 1950);
FORCEPROP 1 LAST PATH I58
J 0
(-1500 2100);
DISPLAY 0.978723 (-1500 2100);
PAINT WHITE (-1500 2100);
DISPLAY INVISIBLE (-1500 2100);
FORCEPROP 1 LAST PART_NUMBER CH4102K6E00
J 0
(-1500 1800);
DISPLAY 0.978723 (-1500 1800);
DISPLAY INVISIBLE (-1500 1800);
FORCEADD Q_CAP..1
(-2050 3275);
FORCEPROP 1 LAST LOCATION C620
J 0
(-2000 3375);
DISPLAY 0.978723 (-2000 3375);
PAINT WHITE (-2000 3375);
FORCEPROP 0 LAST $SEC 1
J 0
(-2000 3425);
DISPLAY 0.680851 (-2000 3425);
PAINT MONO (-2000 3425);
DISPLAY INVISIBLE (-2000 3425);
FORCEPROP 0 LAST CDS_SEC 1
J 0
(-2000 3425);
DISPLAY 0.680851 (-2000 3425);
DISPLAY INVISIBLE (-2000 3425);
FORCEPROP 1 LASTPIN (-2050 3375) $PN 1
J 0
(-2040 3355);
DISPLAY 0.787234 (-2040 3355);
PAINT MONO (-2040 3355);
FORCEPROP 1 LASTPIN (-2050 3175) $PN 2
J 0
(-2040 3155);
DISPLAY 0.787234 (-2040 3155);
PAINT MONO (-2040 3155);
FORCEPROP 1 LAST MATERIAL X6S
J 0
(-2000 3175);
DISPLAY 0.510638 (-2000 3175);
FORCEPROP 1 LAST VALUE 1UF
J 0
(-2000 3325);
DISPLAY 0.510638 (-2000 3325);
FORCEPROP 1 LAST VOLTAGE 4V
J 0
(-2000 3275);
DISPLAY 0.510638 (-2000 3275);
FORCEPROP 1 LAST TOLERANCE 20%
J 0
(-2000 3225);
DISPLAY 0.510638 (-2000 3225);
FORCEPROP 1 LAST PACK_TYPE 0201
J 0
(-2000 3125);
DISPLAY 0.510638 (-2000 3125);
FORCEPROP 2 LAST CDS_LIB pure_quanta
J 0
(-2050 3275);
DISPLAY INVISIBLE (-2050 3275);
FORCEPROP 1 LAST PATH I59
J 0
(-2000 3425);
DISPLAY 0.978723 (-2000 3425);
PAINT WHITE (-2000 3425);
DISPLAY INVISIBLE (-2000 3425);
FORCEPROP 1 LAST PART_NUMBER CH-10KMEE00
J 0
(-2000 3125);
DISPLAY 0.510638 (-2000 3125);
DISPLAY INVISIBLE (-2000 3125);
FORCEADD UNIVERSAL_GND..1
(-6675 2400);
FORCEPROP 3 LASTPIN (-6675 2450) SIG_NAME GND\g
J 0
(-6665 2460);
DISPLAY 0.659574 (-6665 2460);
PAINT MONO (-6665 2460);
DISPLAY INVISIBLE (-6665 2460);
FORCEPROP 2 LAST CDS_LIB pure_quanta_power
J 0
(-6675 2400);
DISPLAY INVISIBLE (-6675 2400);
FORCEPROP 1 LAST HDL_POWER GND
J 1
(-6650 2325);
DISPLAY 0.872340 (-6650 2325);
PAINT GREEN (-6650 2325);
DISPLAY INVISIBLE (-6650 2325);
FORCEPROP 1 LAST PATH I6
J 0
(-6600 2400);
DISPLAY 0.872340 (-6600 2400);
PAINT AQUA (-6600 2400);
DISPLAY INVISIBLE (-6600 2400);
FORCEADD Q_CAP..1
(-1575 3275);
FORCEPROP 1 LAST LOCATION C613
J 0
(-1525 3375);
DISPLAY 0.978723 (-1525 3375);
PAINT WHITE (-1525 3375);
FORCEPROP 0 LAST $SEC 1
J 0
(-1525 3425);
DISPLAY 0.680851 (-1525 3425);
PAINT MONO (-1525 3425);
DISPLAY INVISIBLE (-1525 3425);
FORCEPROP 0 LAST CDS_SEC 1
J 0
(-1525 3425);
DISPLAY 0.680851 (-1525 3425);
DISPLAY INVISIBLE (-1525 3425);
FORCEPROP 1 LASTPIN (-1575 3375) $PN 1
J 0
(-1565 3355);
DISPLAY 0.787234 (-1565 3355);
PAINT MONO (-1565 3355);
FORCEPROP 1 LASTPIN (-1575 3175) $PN 2
J 0
(-1565 3155);
DISPLAY 0.787234 (-1565 3155);
PAINT MONO (-1565 3155);
FORCEPROP 1 LAST PACK_TYPE 0201
J 0
(-1525 3125);
DISPLAY 0.510638 (-1525 3125);
FORCEPROP 1 LAST TOLERANCE 20%
J 0
(-1525 3225);
DISPLAY 0.510638 (-1525 3225);
FORCEPROP 1 LAST VOLTAGE 4V
J 0
(-1525 3275);
DISPLAY 0.510638 (-1525 3275);
FORCEPROP 1 LAST VALUE 1UF
J 0
(-1525 3325);
DISPLAY 0.510638 (-1525 3325);
FORCEPROP 1 LAST MATERIAL X6S
J 0
(-1525 3175);
DISPLAY 0.510638 (-1525 3175);
FORCEPROP 2 LAST CDS_LIB pure_quanta
J 0
(-1575 3275);
DISPLAY INVISIBLE (-1575 3275);
FORCEPROP 1 LAST PATH I61
J 0
(-1525 3425);
DISPLAY 0.978723 (-1525 3425);
PAINT WHITE (-1525 3425);
DISPLAY INVISIBLE (-1525 3425);
FORCEPROP 1 LAST PART_NUMBER CH-10KMEE00
J 0
(-1525 3125);
DISPLAY 0.510638 (-1525 3125);
DISPLAY INVISIBLE (-1525 3125);
FORCEADD UNIVERSAL_GND..1
(-1050 2225);
FORCEPROP 3 LASTPIN (-1050 2275) SIG_NAME GND\g
J 0
(-1040 2285);
DISPLAY 0.659574 (-1040 2285);
PAINT MONO (-1040 2285);
DISPLAY INVISIBLE (-1040 2285);
FORCEPROP 2 LAST CDS_LIB pure_quanta_power
J 0
(-1050 2225);
DISPLAY INVISIBLE (-1050 2225);
FORCEPROP 1 LAST HDL_POWER GND
J 1
(-1025 2150);
DISPLAY 0.872340 (-1025 2150);
PAINT GREEN (-1025 2150);
DISPLAY INVISIBLE (-1025 2150);
FORCEPROP 1 LAST PATH I62
J 0
(-975 2225);
DISPLAY 0.872340 (-975 2225);
PAINT AQUA (-975 2225);
DISPLAY INVISIBLE (-975 2225);
FORCEADD Q_INDUCTOR..1
(-4000 4175);
FORCEPROP 1 LAST LOCATION L14
J 0
(-4125 4335);
DISPLAY 0.723404 (-4125 4335);
PAINT GREEN (-4125 4335);
FORCEPROP 0 LAST $SEC 1
J 0
(-4125 4475);
DISPLAY 0.680851 (-4125 4475);
PAINT MONO (-4125 4475);
DISPLAY INVISIBLE (-4125 4475);
FORCEPROP 0 LAST CDS_SEC 1
J 0
(-4125 4475);
DISPLAY 0.680851 (-4125 4475);
DISPLAY INVISIBLE (-4125 4475);
FORCEPROP 0 LASTPIN (-4100 4150) $PN 1
J 2
(-4110 4160);
DISPLAY 0.680851 (-4110 4160);
PAINT MONO (-4110 4160);
FORCEPROP 0 LASTPIN (-3900 4150) $PN 2
J 0
(-3890 4160);
DISPLAY 0.680851 (-3890 4160);
PAINT MONO (-3890 4160);
FORCEPROP 2 LAST VALUE 100NH/16A
J 0
(-4125 4425);
DISPLAY 0.680851 (-4125 4425);
FORCEPROP 2 LAST PACK_TYPE SMLF
J 0
(-4125 4375);
DISPLAY 0.680851 (-4125 4375);
FORCEPROP 1 LAST MATERIAL IND
J 0
(-4125 4230);
DISPLAY 0.723404 (-4125 4230);
PAINT GREEN (-4125 4230);
FORCEPROP 2 LAST CDS_LIB pure_quanta
J 0
(-4000 4175);
DISPLAY INVISIBLE (-4000 4175);
FORCEPROP 1 LAST NEEDS_NO_SIZE TRUE
J 0
(-4000 4175);
DISPLAY 0.468085 (-4000 4175);
PAINT GREEN (-4000 4175);
DISPLAY INVISIBLE (-4000 4175);
FORCEPROP 1 LAST PATH I63
J 0
(-3925 4230);
DISPLAY 0.723404 (-3925 4230);
PAINT GREEN (-3925 4230);
DISPLAY INVISIBLE (-3925 4230);
FORCEPROP 1 LAST PART_NUMBER CV+10G0MZ04
J 0
(-4125 4285);
DISPLAY 0.723404 (-4125 4285);
PAINT GREEN (-4125 4285);
DISPLAY INVISIBLE (-4125 4285);
FORCEADD Q_CAP..1
(-3650 3900);
FORCEPROP 1 LAST LOCATION C625
J 0
(-3600 4000);
DISPLAY 0.978723 (-3600 4000);
PAINT WHITE (-3600 4000);
FORCEPROP 0 LAST $SEC 1
J 0
(-3600 4050);
DISPLAY 0.680851 (-3600 4050);
PAINT MONO (-3600 4050);
DISPLAY INVISIBLE (-3600 4050);
FORCEPROP 0 LAST CDS_SEC 1
J 0
(-3600 4050);
DISPLAY 0.680851 (-3600 4050);
DISPLAY INVISIBLE (-3600 4050);
FORCEPROP 1 LASTPIN (-3650 4000) $PN 1
J 0
(-3640 3980);
DISPLAY 0.787234 (-3640 3980);
PAINT MONO (-3640 3980);
FORCEPROP 1 LASTPIN (-3650 3800) $PN 2
J 0
(-3640 3780);
DISPLAY 0.787234 (-3640 3780);
PAINT MONO (-3640 3780);
FORCEPROP 1 LAST TOLERANCE 20%
J 0
(-3600 3850);
DISPLAY 0.510638 (-3600 3850);
FORCEPROP 1 LAST MATERIAL X6S
J 0
(-3600 3800);
DISPLAY 0.510638 (-3600 3800);
FORCEPROP 1 LAST VOLTAGE 4V
J 0
(-3600 3900);
DISPLAY 0.510638 (-3600 3900);
FORCEPROP 1 LAST VALUE 100UF
J 0
(-3600 3950);
DISPLAY 0.510638 (-3600 3950);
FORCEPROP 1 LAST PACK_TYPE C0805
J 0
(-3600 3750);
DISPLAY 0.510638 (-3600 3750);
FORCEPROP 2 LAST CDS_LIB pure_quanta
J 0
(-3650 3900);
DISPLAY INVISIBLE (-3650 3900);
FORCEPROP 1 LAST PATH I64
J 0
(-3600 4050);
DISPLAY 0.978723 (-3600 4050);
PAINT WHITE (-3600 4050);
DISPLAY INVISIBLE (-3600 4050);
FORCEPROP 1 LAST PART_NUMBER CH710KMEA01
J 0
(-3600 3750);
DISPLAY 0.404255 (-3600 3750);
DISPLAY INVISIBLE (-3600 3750);
FORCEADD Q_CAP..1
(-3425 3900);
FORCEPROP 1 LAST LOCATION C628
J 0
(-3375 4000);
DISPLAY 0.978723 (-3375 4000);
PAINT WHITE (-3375 4000);
FORCEPROP 0 LAST $SEC 1
J 0
(-3375 4050);
DISPLAY 0.680851 (-3375 4050);
PAINT MONO (-3375 4050);
DISPLAY INVISIBLE (-3375 4050);
FORCEPROP 0 LAST CDS_SEC 1
J 0
(-3375 4050);
DISPLAY 0.680851 (-3375 4050);
DISPLAY INVISIBLE (-3375 4050);
FORCEPROP 1 LASTPIN (-3425 4000) $PN 1
J 0
(-3415 3980);
DISPLAY 0.787234 (-3415 3980);
PAINT MONO (-3415 3980);
FORCEPROP 1 LASTPIN (-3425 3800) $PN 2
J 0
(-3415 3780);
DISPLAY 0.787234 (-3415 3780);
PAINT MONO (-3415 3780);
FORCEPROP 1 LAST VOLTAGE 4V
J 0
(-3375 3900);
DISPLAY 0.510638 (-3375 3900);
FORCEPROP 1 LAST MATERIAL X6S
J 0
(-3375 3800);
DISPLAY 0.510638 (-3375 3800);
FORCEPROP 1 LAST PACK_TYPE C0805
J 0
(-3375 3750);
DISPLAY 0.510638 (-3375 3750);
FORCEPROP 1 LAST VALUE 100UF
J 0
(-3375 3950);
DISPLAY 0.510638 (-3375 3950);
FORCEPROP 1 LAST TOLERANCE 20%
J 0
(-3375 3850);
DISPLAY 0.510638 (-3375 3850);
FORCEPROP 2 LAST CDS_LIB pure_quanta
J 0
(-3425 3900);
DISPLAY INVISIBLE (-3425 3900);
FORCEPROP 1 LAST PATH I65
J 0
(-3375 4050);
DISPLAY 0.978723 (-3375 4050);
PAINT WHITE (-3375 4050);
DISPLAY INVISIBLE (-3375 4050);
FORCEPROP 1 LAST PART_NUMBER CH710KMEA01
J 0
(-3375 3750);
DISPLAY 0.404255 (-3375 3750);
DISPLAY INVISIBLE (-3375 3750);
FORCEADD VCC_CORE..1
(-3650 4550);
FORCEPROP 3 LASTPIN (-3650 4500) SIG_NAME P0V9_CPU0_RT1_2A\g
J 0
(-3640 4510);
DISPLAY 0.659574 (-3640 4510);
PAINT MONO (-3640 4510);
DISPLAY INVISIBLE (-3640 4510);
FORCEPROP 1 LAST HDL_POWER P0V9_CPU0_RT1_2A
J 1
(-3650 4600);
DISPLAY 0.617021 (-3650 4600);
PAINT GREEN (-3650 4600);
FORCEPROP 2 LAST CDS_LIB pure_quanta_power
J 0
(-3650 4550);
DISPLAY INVISIBLE (-3650 4550);
FORCEPROP 1 LAST PATH I66
J 0
(-3600 4575);
DISPLAY 0.872340 (-3600 4575);
PAINT AQUA (-3600 4575);
DISPLAY INVISIBLE (-3600 4575);
FORCEADD Q_CAP..1
(-3600 5175);
FORCEPROP 1 LAST LOCATION C632
J 0
(-3550 5275);
DISPLAY 0.978723 (-3550 5275);
PAINT WHITE (-3550 5275);
FORCEPROP 0 LAST $SEC 1
J 0
(-3550 5325);
DISPLAY 0.680851 (-3550 5325);
PAINT MONO (-3550 5325);
DISPLAY INVISIBLE (-3550 5325);
FORCEPROP 0 LAST CDS_SEC 1
J 0
(-3550 5325);
DISPLAY 0.680851 (-3550 5325);
DISPLAY INVISIBLE (-3550 5325);
FORCEPROP 1 LASTPIN (-3600 5275) $PN 1
J 0
(-3590 5255);
DISPLAY 0.787234 (-3590 5255);
PAINT MONO (-3590 5255);
FORCEPROP 1 LASTPIN (-3600 5075) $PN 2
J 0
(-3590 5055);
DISPLAY 0.787234 (-3590 5055);
PAINT MONO (-3590 5055);
FORCEPROP 1 LAST TOLERANCE 20%
J 0
(-3550 5125);
DISPLAY 0.510638 (-3550 5125);
FORCEPROP 1 LAST PACK_TYPE C0805
J 0
(-3550 5025);
DISPLAY 0.510638 (-3550 5025);
FORCEPROP 1 LAST VOLTAGE 4V
J 0
(-3550 5175);
DISPLAY 0.510638 (-3550 5175);
FORCEPROP 1 LAST VALUE 100UF
J 0
(-3550 5225);
DISPLAY 0.510638 (-3550 5225);
FORCEPROP 1 LAST MATERIAL X6S
J 0
(-3550 5075);
DISPLAY 0.510638 (-3550 5075);
FORCEPROP 2 LAST CDS_LIB pure_quanta
J 0
(-3600 5175);
DISPLAY INVISIBLE (-3600 5175);
FORCEPROP 1 LAST PATH I67
J 0
(-3550 5325);
DISPLAY 0.978723 (-3550 5325);
PAINT WHITE (-3550 5325);
DISPLAY INVISIBLE (-3550 5325);
FORCEPROP 1 LAST PART_NUMBER CH710KMEA01
J 0
(-3550 5025);
DISPLAY 0.404255 (-3550 5025);
DISPLAY INVISIBLE (-3550 5025);
FORCEADD Q_CAP..1
(-3325 5175);
FORCEPROP 1 LAST LOCATION C636
J 0
(-3275 5275);
DISPLAY 0.978723 (-3275 5275);
PAINT WHITE (-3275 5275);
FORCEPROP 0 LAST $SEC 1
J 0
(-3275 5325);
DISPLAY 0.680851 (-3275 5325);
PAINT MONO (-3275 5325);
DISPLAY INVISIBLE (-3275 5325);
FORCEPROP 0 LAST CDS_SEC 1
J 0
(-3275 5325);
DISPLAY 0.680851 (-3275 5325);
DISPLAY INVISIBLE (-3275 5325);
FORCEPROP 1 LASTPIN (-3325 5275) $PN 1
J 0
(-3315 5255);
DISPLAY 0.787234 (-3315 5255);
PAINT MONO (-3315 5255);
FORCEPROP 1 LASTPIN (-3325 5075) $PN 2
J 0
(-3315 5055);
DISPLAY 0.787234 (-3315 5055);
PAINT MONO (-3315 5055);
FORCEPROP 1 LAST VALUE 22UF
J 0
(-3275 5225);
DISPLAY 0.510638 (-3275 5225);
FORCEPROP 1 LAST PACK_TYPE C0402
J 0
(-3275 5025);
DISPLAY 0.510638 (-3275 5025);
FORCEPROP 1 LAST VOLTAGE 4V
J 0
(-3275 5175);
DISPLAY 0.510638 (-3275 5175);
FORCEPROP 1 LAST MATERIAL X6S
J 0
(-3275 5075);
DISPLAY 0.510638 (-3275 5075);
FORCEPROP 1 LAST TOLERANCE 20%
J 0
(-3275 5125);
DISPLAY 0.510638 (-3275 5125);
FORCEPROP 2 LAST CDS_LIB pure_quanta
J 0
(-3325 5175);
DISPLAY INVISIBLE (-3325 5175);
FORCEPROP 1 LAST PATH I68
J 0
(-3275 5325);
DISPLAY 0.978723 (-3275 5325);
PAINT WHITE (-3275 5325);
DISPLAY INVISIBLE (-3275 5325);
FORCEPROP 1 LAST PART_NUMBER CH622KMEB02
J 0
(-3275 5025);
DISPLAY 0.978723 (-3275 5025);
DISPLAY INVISIBLE (-3275 5025);
FORCEADD Q_CAP..1
(-3200 3900);
FORCEPROP 1 LAST LOCATION C633
J 0
(-3150 4000);
DISPLAY 0.978723 (-3150 4000);
PAINT WHITE (-3150 4000);
FORCEPROP 0 LAST $SEC 1
J 0
(-3150 4050);
DISPLAY 0.680851 (-3150 4050);
PAINT MONO (-3150 4050);
DISPLAY INVISIBLE (-3150 4050);
FORCEPROP 0 LAST CDS_SEC 1
J 0
(-3150 4050);
DISPLAY 0.680851 (-3150 4050);
DISPLAY INVISIBLE (-3150 4050);
FORCEPROP 1 LASTPIN (-3200 4000) $PN 1
J 0
(-3190 3980);
DISPLAY 0.787234 (-3190 3980);
PAINT MONO (-3190 3980);
FORCEPROP 1 LASTPIN (-3200 3800) $PN 2
J 0
(-3190 3780);
DISPLAY 0.787234 (-3190 3780);
PAINT MONO (-3190 3780);
FORCEPROP 1 LAST VALUE 100UF
J 0
(-3150 3950);
DISPLAY 0.510638 (-3150 3950);
FORCEPROP 1 LAST VOLTAGE 4V
J 0
(-3150 3900);
DISPLAY 0.510638 (-3150 3900);
FORCEPROP 1 LAST TOLERANCE 20%
J 0
(-3150 3850);
DISPLAY 0.510638 (-3150 3850);
FORCEPROP 1 LAST MATERIAL X6S
J 0
(-3150 3800);
DISPLAY 0.510638 (-3150 3800);
FORCEPROP 1 LAST PACK_TYPE C0805
J 0
(-3150 3750);
DISPLAY 0.510638 (-3150 3750);
FORCEPROP 2 LAST CDS_LIB pure_quanta
J 0
(-3200 3900);
DISPLAY INVISIBLE (-3200 3900);
FORCEPROP 1 LAST PATH I69
J 0
(-3150 4050);
DISPLAY 0.978723 (-3150 4050);
PAINT WHITE (-3150 4050);
DISPLAY INVISIBLE (-3150 4050);
FORCEPROP 1 LAST PART_NUMBER CH710KMEA01
J 0
(-3150 3750);
DISPLAY 0.404255 (-3150 3750);
DISPLAY INVISIBLE (-3150 3750);
FORCEADD Q_CAP..1
(-6675 2800);
FORCEPROP 1 LAST LOCATION C601
J 0
(-6625 2900);
DISPLAY 0.978723 (-6625 2900);
PAINT WHITE (-6625 2900);
FORCEPROP 0 LAST $SEC 1
J 0
(-6625 2950);
DISPLAY 0.680851 (-6625 2950);
PAINT MONO (-6625 2950);
DISPLAY INVISIBLE (-6625 2950);
FORCEPROP 0 LAST CDS_SEC 1
J 0
(-6625 2950);
DISPLAY 0.680851 (-6625 2950);
DISPLAY INVISIBLE (-6625 2950);
FORCEPROP 1 LASTPIN (-6675 2900) $PN 1
J 0
(-6665 2880);
DISPLAY 0.787234 (-6665 2880);
PAINT MONO (-6665 2880);
FORCEPROP 1 LASTPIN (-6675 2700) $PN 2
J 0
(-6665 2680);
DISPLAY 0.787234 (-6665 2680);
PAINT MONO (-6665 2680);
FORCEPROP 1 LAST VOLTAGE 10V
J 0
(-6625 2800);
DISPLAY 0.638298 (-6625 2800);
FORCEPROP 1 LAST TOLERANCE 10%
J 0
(-6625 2750);
DISPLAY 0.638298 (-6625 2750);
FORCEPROP 1 LAST VALUE 0.1UF
J 0
(-6625 2850);
DISPLAY 0.638298 (-6625 2850);
FORCEPROP 1 LAST MATERIAL X7S
J 0
(-6625 2700);
DISPLAY 0.638298 (-6625 2700);
FORCEPROP 1 LAST PACK_TYPE C0201
J 0
(-6625 2650);
DISPLAY 0.638298 (-6625 2650);
FORCEPROP 2 LAST CDS_LIB pure_quanta
J 0
(-6675 2800);
DISPLAY INVISIBLE (-6675 2800);
FORCEPROP 1 LAST PATH I7
J 0
(-6625 2950);
DISPLAY 0.978723 (-6625 2950);
PAINT WHITE (-6625 2950);
DISPLAY INVISIBLE (-6625 2950);
FORCEPROP 1 LAST PART_NUMBER CH4102K6E00
J 0
(-6625 2650);
DISPLAY 0.978723 (-6625 2650);
DISPLAY INVISIBLE (-6625 2650);
FORCEADD Q_CAP..1
(-2975 3900);
FORCEPROP 1 LAST LOCATION C637
J 0
(-2925 4000);
DISPLAY 0.978723 (-2925 4000);
PAINT WHITE (-2925 4000);
FORCEPROP 0 LAST $SEC 1
J 0
(-2925 4050);
DISPLAY 0.680851 (-2925 4050);
PAINT MONO (-2925 4050);
DISPLAY INVISIBLE (-2925 4050);
FORCEPROP 0 LAST CDS_SEC 1
J 0
(-2925 4050);
DISPLAY 0.680851 (-2925 4050);
DISPLAY INVISIBLE (-2925 4050);
FORCEPROP 1 LASTPIN (-2975 4000) $PN 1
J 0
(-2965 3980);
DISPLAY 0.787234 (-2965 3980);
PAINT MONO (-2965 3980);
FORCEPROP 1 LASTPIN (-2975 3800) $PN 2
J 0
(-2965 3780);
DISPLAY 0.787234 (-2965 3780);
PAINT MONO (-2965 3780);
FORCEPROP 1 LAST VOLTAGE 4V
J 0
(-2925 3900);
DISPLAY 0.510638 (-2925 3900);
FORCEPROP 1 LAST MATERIAL X6S
J 0
(-2925 3800);
DISPLAY 0.510638 (-2925 3800);
FORCEPROP 1 LAST TOLERANCE 20%
J 0
(-2925 3850);
DISPLAY 0.510638 (-2925 3850);
FORCEPROP 1 LAST PACK_TYPE C0805
J 0
(-2925 3750);
DISPLAY 0.510638 (-2925 3750);
FORCEPROP 1 LAST VALUE 100UF
J 0
(-2925 3950);
DISPLAY 0.510638 (-2925 3950);
FORCEPROP 2 LAST CDS_LIB pure_quanta
J 0
(-2975 3900);
DISPLAY INVISIBLE (-2975 3900);
FORCEPROP 1 LAST PATH I70
J 0
(-2925 4050);
DISPLAY 0.978723 (-2925 4050);
PAINT WHITE (-2925 4050);
DISPLAY INVISIBLE (-2925 4050);
FORCEPROP 1 LAST PART_NUMBER CH710KMEA01
J 0
(-2925 3750);
DISPLAY 0.404255 (-2925 3750);
DISPLAY INVISIBLE (-2925 3750);
FORCEADD Q_CAP..1
(-2725 3900);
FORCEPROP 1 LAST LOCATION C634
J 0
(-2675 4000);
DISPLAY 0.978723 (-2675 4000);
PAINT WHITE (-2675 4000);
FORCEPROP 0 LAST $SEC 1
J 0
(-2675 4050);
DISPLAY 0.680851 (-2675 4050);
PAINT MONO (-2675 4050);
DISPLAY INVISIBLE (-2675 4050);
FORCEPROP 0 LAST CDS_SEC 1
J 0
(-2675 4050);
DISPLAY 0.680851 (-2675 4050);
DISPLAY INVISIBLE (-2675 4050);
FORCEPROP 1 LASTPIN (-2725 4000) $PN 1
J 0
(-2715 3980);
DISPLAY 0.787234 (-2715 3980);
PAINT MONO (-2715 3980);
FORCEPROP 1 LASTPIN (-2725 3800) $PN 2
J 0
(-2715 3780);
DISPLAY 0.787234 (-2715 3780);
PAINT MONO (-2715 3780);
FORCEPROP 1 LAST TOLERANCE 20%
J 0
(-2675 3850);
DISPLAY 0.510638 (-2675 3850);
FORCEPROP 1 LAST VOLTAGE 4V
J 0
(-2675 3900);
DISPLAY 0.510638 (-2675 3900);
FORCEPROP 1 LAST MATERIAL X6S
J 0
(-2675 3800);
DISPLAY 0.510638 (-2675 3800);
FORCEPROP 1 LAST VALUE 22UF
J 0
(-2675 3950);
DISPLAY 0.510638 (-2675 3950);
FORCEPROP 1 LAST PACK_TYPE C0402
J 0
(-2675 3750);
DISPLAY 0.510638 (-2675 3750);
FORCEPROP 2 LAST CDS_LIB pure_quanta
J 0
(-2725 3900);
DISPLAY INVISIBLE (-2725 3900);
FORCEPROP 1 LAST PATH I71
J 0
(-2675 4050);
DISPLAY 0.978723 (-2675 4050);
PAINT WHITE (-2675 4050);
DISPLAY INVISIBLE (-2675 4050);
FORCEPROP 1 LAST PART_NUMBER CH622KMEB02
J 0
(-2675 3750);
DISPLAY 0.978723 (-2675 3750);
DISPLAY INVISIBLE (-2675 3750);
FORCEADD Q_CAP..1
(-2500 3900);
FORCEPROP 1 LAST LOCATION C663
J 0
(-2450 4000);
DISPLAY 0.978723 (-2450 4000);
PAINT WHITE (-2450 4000);
FORCEPROP 0 LAST $SEC 1
J 0
(-2450 4050);
DISPLAY 0.680851 (-2450 4050);
PAINT MONO (-2450 4050);
DISPLAY INVISIBLE (-2450 4050);
FORCEPROP 0 LAST CDS_SEC 1
J 0
(-2450 4050);
DISPLAY 0.680851 (-2450 4050);
DISPLAY INVISIBLE (-2450 4050);
FORCEPROP 1 LASTPIN (-2500 4000) $PN 1
J 0
(-2490 3980);
DISPLAY 0.787234 (-2490 3980);
PAINT MONO (-2490 3980);
FORCEPROP 1 LASTPIN (-2500 3800) $PN 2
J 0
(-2490 3780);
DISPLAY 0.787234 (-2490 3780);
PAINT MONO (-2490 3780);
FORCEPROP 1 LAST TOLERANCE 20%
J 0
(-2450 3850);
DISPLAY 0.510638 (-2450 3850);
FORCEPROP 1 LAST MATERIAL X6S
J 0
(-2450 3800);
DISPLAY 0.510638 (-2450 3800);
FORCEPROP 1 LAST VOLTAGE 4V
J 0
(-2450 3900);
DISPLAY 0.510638 (-2450 3900);
FORCEPROP 1 LAST PACK_TYPE C0402
J 0
(-2450 3750);
DISPLAY 0.510638 (-2450 3750);
FORCEPROP 1 LAST VALUE 22UF
J 0
(-2450 3950);
DISPLAY 0.510638 (-2450 3950);
FORCEPROP 2 LAST CDS_LIB pure_quanta
J 0
(-2500 3900);
DISPLAY INVISIBLE (-2500 3900);
FORCEPROP 1 LAST PATH I72
J 0
(-2450 4050);
DISPLAY 0.978723 (-2450 4050);
PAINT WHITE (-2450 4050);
DISPLAY INVISIBLE (-2450 4050);
FORCEPROP 1 LAST PART_NUMBER CH622KMEB02
J 0
(-2450 3750);
DISPLAY 0.978723 (-2450 3750);
DISPLAY INVISIBLE (-2450 3750);
FORCEADD Q_CAP..1
(-2275 3900);
FORCEPROP 1 LAST LOCATION C630
J 0
(-2225 4000);
DISPLAY 0.978723 (-2225 4000);
PAINT WHITE (-2225 4000);
FORCEPROP 0 LAST $SEC 1
J 0
(-2225 4050);
DISPLAY 0.680851 (-2225 4050);
PAINT MONO (-2225 4050);
DISPLAY INVISIBLE (-2225 4050);
FORCEPROP 0 LAST CDS_SEC 1
J 0
(-2225 4050);
DISPLAY 0.680851 (-2225 4050);
DISPLAY INVISIBLE (-2225 4050);
FORCEPROP 1 LASTPIN (-2275 4000) $PN 1
J 0
(-2265 3980);
DISPLAY 0.787234 (-2265 3980);
PAINT MONO (-2265 3980);
FORCEPROP 1 LASTPIN (-2275 3800) $PN 2
J 0
(-2265 3780);
DISPLAY 0.787234 (-2265 3780);
PAINT MONO (-2265 3780);
FORCEPROP 1 LAST PACK_TYPE C0402
J 0
(-2225 3750);
DISPLAY 0.510638 (-2225 3750);
FORCEPROP 1 LAST VOLTAGE 4V
J 0
(-2225 3900);
DISPLAY 0.510638 (-2225 3900);
FORCEPROP 1 LAST MATERIAL X6S
J 0
(-2225 3800);
DISPLAY 0.510638 (-2225 3800);
FORCEPROP 1 LAST VALUE 22UF
J 0
(-2225 3950);
DISPLAY 0.510638 (-2225 3950);
FORCEPROP 1 LAST TOLERANCE 20%
J 0
(-2225 3850);
DISPLAY 0.510638 (-2225 3850);
FORCEPROP 2 LAST CDS_LIB pure_quanta
J 0
(-2275 3900);
DISPLAY INVISIBLE (-2275 3900);
FORCEPROP 1 LAST PATH I73
J 0
(-2225 4050);
DISPLAY 0.978723 (-2225 4050);
PAINT WHITE (-2225 4050);
DISPLAY INVISIBLE (-2225 4050);
FORCEPROP 1 LAST PART_NUMBER CH622KMEB02
J 0
(-2225 3750);
DISPLAY 0.978723 (-2225 3750);
DISPLAY INVISIBLE (-2225 3750);
FORCEADD Q_CAP..1
(-3000 5150);
FORCEPROP 1 LAST LOCATION C646
J 0
(-2950 5250);
DISPLAY 0.978723 (-2950 5250);
PAINT WHITE (-2950 5250);
FORCEPROP 0 LAST $SEC 1
J 0
(-2950 5300);
DISPLAY 0.680851 (-2950 5300);
PAINT MONO (-2950 5300);
DISPLAY INVISIBLE (-2950 5300);
FORCEPROP 0 LAST CDS_SEC 1
J 0
(-2950 5300);
DISPLAY 0.680851 (-2950 5300);
DISPLAY INVISIBLE (-2950 5300);
FORCEPROP 1 LASTPIN (-3000 5250) $PN 1
J 0
(-2990 5230);
DISPLAY 0.787234 (-2990 5230);
PAINT MONO (-2990 5230);
FORCEPROP 1 LASTPIN (-3000 5050) $PN 2
J 0
(-2990 5030);
DISPLAY 0.787234 (-2990 5030);
PAINT MONO (-2990 5030);
FORCEPROP 1 LAST VALUE 10UF
J 0
(-2950 5200);
DISPLAY 0.510638 (-2950 5200);
FORCEPROP 1 LAST MATERIAL X6S
J 0
(-2950 5050);
DISPLAY 0.510638 (-2950 5050);
FORCEPROP 1 LAST PACK_TYPE C0402
J 0
(-2950 5000);
DISPLAY 0.510638 (-2950 5000);
FORCEPROP 1 LAST VOLTAGE 6.3V
J 0
(-2950 5150);
DISPLAY 0.510638 (-2950 5150);
FORCEPROP 1 LAST TOLERANCE 20%
J 0
(-2950 5100);
DISPLAY 0.510638 (-2950 5100);
FORCEPROP 2 LAST CDS_LIB pure_quanta
J 0
(-3000 5150);
DISPLAY INVISIBLE (-3000 5150);
FORCEPROP 1 LAST PATH I74
J 0
(-2950 5300);
DISPLAY 0.978723 (-2950 5300);
PAINT WHITE (-2950 5300);
DISPLAY INVISIBLE (-2950 5300);
FORCEPROP 1 LAST PART_NUMBER CH6101MEB01
J 0
(-2950 5000);
DISPLAY 0.978723 (-2950 5000);
DISPLAY INVISIBLE (-2950 5000);
FORCEADD Q_CAP..1
(-2700 5150);
FORCEPROP 1 LAST LOCATION C651
J 0
(-2650 5250);
DISPLAY 0.978723 (-2650 5250);
PAINT WHITE (-2650 5250);
FORCEPROP 0 LAST $SEC 1
J 0
(-2650 5300);
DISPLAY 0.680851 (-2650 5300);
PAINT MONO (-2650 5300);
DISPLAY INVISIBLE (-2650 5300);
FORCEPROP 0 LAST CDS_SEC 1
J 0
(-2650 5300);
DISPLAY 0.680851 (-2650 5300);
DISPLAY INVISIBLE (-2650 5300);
FORCEPROP 1 LASTPIN (-2700 5250) $PN 1
J 0
(-2690 5230);
DISPLAY 0.787234 (-2690 5230);
PAINT MONO (-2690 5230);
FORCEPROP 1 LASTPIN (-2700 5050) $PN 2
J 0
(-2690 5030);
DISPLAY 0.787234 (-2690 5030);
PAINT MONO (-2690 5030);
FORCEPROP 1 LAST VOLTAGE 6.3V
J 0
(-2650 5150);
DISPLAY 0.510638 (-2650 5150);
FORCEPROP 1 LAST VALUE 4.7UF
J 0
(-2650 5200);
DISPLAY 0.510638 (-2650 5200);
FORCEPROP 1 LAST MATERIAL X6S
J 0
(-2650 5050);
DISPLAY 0.510638 (-2650 5050);
FORCEPROP 1 LAST PACK_TYPE 0402
J 0
(-2650 5000);
DISPLAY 0.510638 (-2650 5000);
FORCEPROP 1 LAST TOLERANCE 20%
J 0
(-2650 5100);
DISPLAY 0.510638 (-2650 5100);
FORCEPROP 2 LAST CDS_LIB pure_quanta
J 0
(-2700 5150);
DISPLAY INVISIBLE (-2700 5150);
FORCEPROP 1 LAST PATH I75
J 0
(-2650 5300);
DISPLAY 0.978723 (-2650 5300);
PAINT WHITE (-2650 5300);
DISPLAY INVISIBLE (-2650 5300);
FORCEPROP 1 LAST PART_NUMBER CH5471MEB01
J 0
(-2650 5000);
DISPLAY 0.978723 (-2650 5000);
DISPLAY INVISIBLE (-2650 5000);
FORCEADD Q_CAP..1
(-2400 5150);
FORCEPROP 1 LAST LOCATION C655
J 0
(-2350 5250);
DISPLAY 0.978723 (-2350 5250);
PAINT WHITE (-2350 5250);
FORCEPROP 0 LAST $SEC 1
J 0
(-2350 5300);
DISPLAY 0.680851 (-2350 5300);
PAINT MONO (-2350 5300);
DISPLAY INVISIBLE (-2350 5300);
FORCEPROP 0 LAST CDS_SEC 1
J 0
(-2350 5300);
DISPLAY 0.680851 (-2350 5300);
DISPLAY INVISIBLE (-2350 5300);
FORCEPROP 1 LASTPIN (-2400 5250) $PN 1
J 0
(-2390 5230);
DISPLAY 0.787234 (-2390 5230);
PAINT MONO (-2390 5230);
FORCEPROP 1 LASTPIN (-2400 5050) $PN 2
J 0
(-2390 5030);
DISPLAY 0.787234 (-2390 5030);
PAINT MONO (-2390 5030);
FORCEPROP 1 LAST MATERIAL X6S
J 0
(-2350 5050);
DISPLAY 0.510638 (-2350 5050);
FORCEPROP 1 LAST PACK_TYPE 0201
J 0
(-2350 5000);
DISPLAY 0.510638 (-2350 5000);
FORCEPROP 1 LAST VOLTAGE 4V
J 0
(-2350 5150);
DISPLAY 0.510638 (-2350 5150);
FORCEPROP 1 LAST VALUE 1UF
J 0
(-2350 5200);
DISPLAY 0.510638 (-2350 5200);
FORCEPROP 1 LAST TOLERANCE 20%
J 0
(-2350 5100);
DISPLAY 0.510638 (-2350 5100);
FORCEPROP 2 LAST CDS_LIB pure_quanta
J 0
(-2400 5150);
DISPLAY INVISIBLE (-2400 5150);
FORCEPROP 1 LAST PATH I76
J 0
(-2350 5300);
DISPLAY 0.978723 (-2350 5300);
PAINT WHITE (-2350 5300);
DISPLAY INVISIBLE (-2350 5300);
FORCEPROP 1 LAST PART_NUMBER CH-10KMEE00
J 0
(-2350 5000);
DISPLAY 0.510638 (-2350 5000);
DISPLAY INVISIBLE (-2350 5000);
FORCEADD Q_CAP..1
(-2050 3900);
FORCEPROP 1 LAST LOCATION C656
J 0
(-2000 4000);
DISPLAY 0.978723 (-2000 4000);
PAINT WHITE (-2000 4000);
FORCEPROP 0 LAST $SEC 1
J 0
(-2000 4050);
DISPLAY 0.680851 (-2000 4050);
PAINT MONO (-2000 4050);
DISPLAY INVISIBLE (-2000 4050);
FORCEPROP 0 LAST CDS_SEC 1
J 0
(-2000 4050);
DISPLAY 0.680851 (-2000 4050);
DISPLAY INVISIBLE (-2000 4050);
FORCEPROP 1 LASTPIN (-2050 4000) $PN 1
J 0
(-2040 3980);
DISPLAY 0.787234 (-2040 3980);
PAINT MONO (-2040 3980);
FORCEPROP 1 LASTPIN (-2050 3800) $PN 2
J 0
(-2040 3780);
DISPLAY 0.787234 (-2040 3780);
PAINT MONO (-2040 3780);
FORCEPROP 1 LAST MATERIAL X6S
J 0
(-2000 3800);
DISPLAY 0.510638 (-2000 3800);
FORCEPROP 1 LAST TOLERANCE 20%
J 0
(-2000 3850);
DISPLAY 0.510638 (-2000 3850);
FORCEPROP 1 LAST VALUE 22UF
J 0
(-2000 3950);
DISPLAY 0.510638 (-2000 3950);
FORCEPROP 1 LAST VOLTAGE 4V
J 0
(-2000 3900);
DISPLAY 0.510638 (-2000 3900);
FORCEPROP 1 LAST PACK_TYPE C0402
J 0
(-2000 3750);
DISPLAY 0.510638 (-2000 3750);
FORCEPROP 2 LAST CDS_LIB pure_quanta
J 0
(-2050 3900);
DISPLAY INVISIBLE (-2050 3900);
FORCEPROP 1 LAST PATH I77
J 0
(-2000 4050);
DISPLAY 0.978723 (-2000 4050);
PAINT WHITE (-2000 4050);
DISPLAY INVISIBLE (-2000 4050);
FORCEPROP 1 LAST PART_NUMBER CH622KMEB02
J 0
(-2000 3750);
DISPLAY 0.978723 (-2000 3750);
DISPLAY INVISIBLE (-2000 3750);
FORCEADD Q_CAP..1
(-1750 3900);
FORCEPROP 1 LAST LOCATION C661
J 0
(-1700 4000);
DISPLAY 0.978723 (-1700 4000);
PAINT WHITE (-1700 4000);
FORCEPROP 0 LAST $SEC 1
J 0
(-1700 4050);
DISPLAY 0.680851 (-1700 4050);
PAINT MONO (-1700 4050);
DISPLAY INVISIBLE (-1700 4050);
FORCEPROP 0 LAST CDS_SEC 1
J 0
(-1700 4050);
DISPLAY 0.680851 (-1700 4050);
DISPLAY INVISIBLE (-1700 4050);
FORCEPROP 1 LASTPIN (-1750 4000) $PN 1
J 0
(-1740 3980);
DISPLAY 0.787234 (-1740 3980);
PAINT MONO (-1740 3980);
FORCEPROP 1 LASTPIN (-1750 3800) $PN 2
J 0
(-1740 3780);
DISPLAY 0.787234 (-1740 3780);
PAINT MONO (-1740 3780);
FORCEPROP 1 LAST VOLTAGE 6.3V
J 0
(-1700 3900);
DISPLAY 0.510638 (-1700 3900);
FORCEPROP 1 LAST PACK_TYPE C0402
J 0
(-1700 3750);
DISPLAY 0.510638 (-1700 3750);
FORCEPROP 1 LAST TOLERANCE 20%
J 0
(-1700 3850);
DISPLAY 0.510638 (-1700 3850);
FORCEPROP 1 LAST MATERIAL X6S
J 0
(-1700 3800);
DISPLAY 0.510638 (-1700 3800);
FORCEPROP 1 LAST VALUE 10UF
J 0
(-1700 3950);
DISPLAY 0.510638 (-1700 3950);
FORCEPROP 2 LAST CDS_LIB pure_quanta
J 0
(-1750 3900);
DISPLAY INVISIBLE (-1750 3900);
FORCEPROP 1 LAST PATH I78
J 0
(-1700 4050);
DISPLAY 0.978723 (-1700 4050);
PAINT WHITE (-1700 4050);
DISPLAY INVISIBLE (-1700 4050);
FORCEPROP 1 LAST PART_NUMBER CH6101MEB01
J 0
(-1700 3750);
DISPLAY 0.978723 (-1700 3750);
DISPLAY INVISIBLE (-1700 3750);
FORCEADD Q_CAP..1
(-1450 3900);
FORCEPROP 1 LAST LOCATION C648
J 0
(-1400 4000);
DISPLAY 0.978723 (-1400 4000);
PAINT WHITE (-1400 4000);
FORCEPROP 0 LAST $SEC 1
J 0
(-1400 4050);
DISPLAY 0.680851 (-1400 4050);
PAINT MONO (-1400 4050);
DISPLAY INVISIBLE (-1400 4050);
FORCEPROP 0 LAST CDS_SEC 1
J 0
(-1400 4050);
DISPLAY 0.680851 (-1400 4050);
DISPLAY INVISIBLE (-1400 4050);
FORCEPROP 1 LASTPIN (-1450 4000) $PN 1
J 0
(-1440 3980);
DISPLAY 0.787234 (-1440 3980);
PAINT MONO (-1440 3980);
FORCEPROP 1 LASTPIN (-1450 3800) $PN 2
J 0
(-1440 3780);
DISPLAY 0.787234 (-1440 3780);
PAINT MONO (-1440 3780);
FORCEPROP 1 LAST VALUE 10UF
J 0
(-1400 3950);
DISPLAY 0.510638 (-1400 3950);
FORCEPROP 1 LAST TOLERANCE 20%
J 0
(-1400 3850);
DISPLAY 0.510638 (-1400 3850);
FORCEPROP 1 LAST MATERIAL X6S
J 0
(-1400 3800);
DISPLAY 0.510638 (-1400 3800);
FORCEPROP 1 LAST VOLTAGE 6.3V
J 0
(-1400 3900);
DISPLAY 0.510638 (-1400 3900);
FORCEPROP 1 LAST PACK_TYPE C0402
J 0
(-1400 3750);
DISPLAY 0.510638 (-1400 3750);
FORCEPROP 2 LAST CDS_LIB pure_quanta
J 0
(-1450 3900);
DISPLAY INVISIBLE (-1450 3900);
FORCEPROP 1 LAST PATH I79
J 0
(-1400 4050);
DISPLAY 0.978723 (-1400 4050);
PAINT WHITE (-1400 4050);
DISPLAY INVISIBLE (-1400 4050);
FORCEPROP 1 LAST PART_NUMBER CH6101MEB01
J 0
(-1400 3750);
DISPLAY 0.978723 (-1400 3750);
DISPLAY INVISIBLE (-1400 3750);
FORCEADD P1V0..1
(-7075 3200);
FORCEPROP 3 LASTPIN (-7075 3150) SIG_NAME P1V8_CPU0_RT1_1A_1D\g
J 0
(-7065 3160);
DISPLAY 0.659574 (-7065 3160);
PAINT MONO (-7065 3160);
DISPLAY INVISIBLE (-7065 3160);
FORCEPROP 1 LAST HDL_POWER P1V8_CPU0_RT1_1A_1D
J 1
(-7075 3250);
DISPLAY 0.489362 (-7075 3250);
PAINT SKYBLUE (-7075 3250);
FORCEPROP 2 LAST CDS_LIB pure_quanta_power
J 0
(-7075 3200);
DISPLAY INVISIBLE (-7075 3200);
FORCEPROP 1 LAST PATH I8
J 0
(-7025 3225);
DISPLAY 0.872340 (-7025 3225);
PAINT AQUA (-7025 3225);
DISPLAY INVISIBLE (-7025 3225);
FORCEADD UNIVERSAL_GND..1
(-1375 4725);
FORCEPROP 3 LASTPIN (-1375 4775) SIG_NAME GND\g
J 0
(-1365 4785);
DISPLAY 0.659574 (-1365 4785);
PAINT MONO (-1365 4785);
DISPLAY INVISIBLE (-1365 4785);
FORCEPROP 2 LAST CDS_LIB pure_quanta_power
J 0
(-1375 4725);
DISPLAY INVISIBLE (-1375 4725);
FORCEPROP 1 LAST HDL_POWER GND
J 1
(-1350 4650);
DISPLAY 0.872340 (-1350 4650);
PAINT GREEN (-1350 4650);
DISPLAY INVISIBLE (-1350 4650);
FORCEPROP 1 LAST PATH I80
J 0
(-1300 4725);
DISPLAY 0.872340 (-1300 4725);
PAINT AQUA (-1300 4725);
DISPLAY INVISIBLE (-1300 4725);
FORCEADD Q_CAP..1
(-2100 5125);
FORCEPROP 1 LAST LOCATION C608
J 0
(-2050 5225);
DISPLAY 0.978723 (-2050 5225);
PAINT WHITE (-2050 5225);
FORCEPROP 0 LAST $SEC 1
J 0
(-2050 5275);
DISPLAY 0.680851 (-2050 5275);
PAINT MONO (-2050 5275);
DISPLAY INVISIBLE (-2050 5275);
FORCEPROP 0 LAST CDS_SEC 1
J 0
(-2050 5275);
DISPLAY 0.680851 (-2050 5275);
DISPLAY INVISIBLE (-2050 5275);
FORCEPROP 1 LASTPIN (-2100 5225) $PN 1
J 0
(-2090 5205);
DISPLAY 0.787234 (-2090 5205);
PAINT MONO (-2090 5205);
FORCEPROP 1 LASTPIN (-2100 5025) $PN 2
J 0
(-2090 5005);
DISPLAY 0.787234 (-2090 5005);
PAINT MONO (-2090 5005);
FORCEPROP 1 LAST TOLERANCE 10%
J 0
(-2050 5075);
DISPLAY 0.638298 (-2050 5075);
FORCEPROP 1 LAST MATERIAL X7S
J 0
(-2050 5025);
DISPLAY 0.638298 (-2050 5025);
FORCEPROP 1 LAST VALUE 0.1UF
J 0
(-2050 5175);
DISPLAY 0.638298 (-2050 5175);
FORCEPROP 1 LAST VOLTAGE 10V
J 0
(-2050 5125);
DISPLAY 0.638298 (-2050 5125);
FORCEPROP 1 LAST PACK_TYPE C0201
J 0
(-2050 4975);
DISPLAY 0.638298 (-2050 4975);
FORCEPROP 2 LAST CDS_LIB pure_quanta
J 0
(-2100 5125);
DISPLAY INVISIBLE (-2100 5125);
FORCEPROP 1 LAST PATH I81
J 0
(-2050 5275);
DISPLAY 0.978723 (-2050 5275);
PAINT WHITE (-2050 5275);
DISPLAY INVISIBLE (-2050 5275);
FORCEPROP 1 LAST PART_NUMBER CH4102K6E00
J 0
(-2050 4975);
DISPLAY 0.978723 (-2050 4975);
DISPLAY INVISIBLE (-2050 4975);
FORCEADD Q_CAP..1
(-1825 5125);
FORCEPROP 1 LAST LOCATION C610
J 0
(-1775 5225);
DISPLAY 0.978723 (-1775 5225);
PAINT WHITE (-1775 5225);
FORCEPROP 0 LAST $SEC 1
J 0
(-1775 5275);
DISPLAY 0.680851 (-1775 5275);
PAINT MONO (-1775 5275);
DISPLAY INVISIBLE (-1775 5275);
FORCEPROP 0 LAST CDS_SEC 1
J 0
(-1775 5275);
DISPLAY 0.680851 (-1775 5275);
DISPLAY INVISIBLE (-1775 5275);
FORCEPROP 1 LASTPIN (-1825 5225) $PN 1
J 0
(-1815 5205);
DISPLAY 0.787234 (-1815 5205);
PAINT MONO (-1815 5205);
FORCEPROP 1 LASTPIN (-1825 5025) $PN 2
J 0
(-1815 5005);
DISPLAY 0.787234 (-1815 5005);
PAINT MONO (-1815 5005);
FORCEPROP 1 LAST TOLERANCE 10%
J 0
(-1775 5075);
DISPLAY 0.638298 (-1775 5075);
FORCEPROP 1 LAST MATERIAL X7S
J 0
(-1775 5025);
DISPLAY 0.638298 (-1775 5025);
FORCEPROP 1 LAST VALUE 0.1UF
J 0
(-1775 5175);
DISPLAY 0.638298 (-1775 5175);
FORCEPROP 1 LAST VOLTAGE 10V
J 0
(-1775 5125);
DISPLAY 0.638298 (-1775 5125);
FORCEPROP 1 LAST PACK_TYPE C0201
J 0
(-1775 4975);
DISPLAY 0.638298 (-1775 4975);
FORCEPROP 2 LAST CDS_LIB pure_quanta
J 0
(-1825 5125);
DISPLAY INVISIBLE (-1825 5125);
FORCEPROP 1 LAST PATH I82
J 0
(-1775 5275);
DISPLAY 0.978723 (-1775 5275);
PAINT WHITE (-1775 5275);
DISPLAY INVISIBLE (-1775 5275);
FORCEPROP 1 LAST PART_NUMBER CH4102K6E00
J 0
(-1775 4975);
DISPLAY 0.978723 (-1775 4975);
DISPLAY INVISIBLE (-1775 4975);
FORCEADD Q_CAP..1
(-1575 5125);
FORCEPROP 1 LAST LOCATION C615
J 0
(-1525 5225);
DISPLAY 0.978723 (-1525 5225);
PAINT WHITE (-1525 5225);
FORCEPROP 0 LAST $SEC 1
J 0
(-1525 5275);
DISPLAY 0.680851 (-1525 5275);
PAINT MONO (-1525 5275);
DISPLAY INVISIBLE (-1525 5275);
FORCEPROP 0 LAST CDS_SEC 1
J 0
(-1525 5275);
DISPLAY 0.680851 (-1525 5275);
DISPLAY INVISIBLE (-1525 5275);
FORCEPROP 1 LASTPIN (-1575 5225) $PN 1
J 0
(-1565 5205);
DISPLAY 0.787234 (-1565 5205);
PAINT MONO (-1565 5205);
FORCEPROP 1 LASTPIN (-1575 5025) $PN 2
J 0
(-1565 5005);
DISPLAY 0.787234 (-1565 5005);
PAINT MONO (-1565 5005);
FORCEPROP 1 LAST VOLTAGE 10V
J 0
(-1525 5125);
DISPLAY 0.638298 (-1525 5125);
FORCEPROP 1 LAST VALUE 0.1UF
J 0
(-1525 5175);
DISPLAY 0.638298 (-1525 5175);
FORCEPROP 1 LAST PACK_TYPE C0201
J 0
(-1525 4975);
DISPLAY 0.638298 (-1525 4975);
FORCEPROP 1 LAST TOLERANCE 10%
J 0
(-1525 5075);
DISPLAY 0.638298 (-1525 5075);
FORCEPROP 1 LAST MATERIAL X7S
J 0
(-1525 5025);
DISPLAY 0.638298 (-1525 5025);
FORCEPROP 2 LAST CDS_LIB pure_quanta
J 0
(-1575 5125);
DISPLAY INVISIBLE (-1575 5125);
FORCEPROP 1 LAST PATH I83
J 0
(-1525 5275);
DISPLAY 0.978723 (-1525 5275);
PAINT WHITE (-1525 5275);
DISPLAY INVISIBLE (-1525 5275);
FORCEPROP 1 LAST PART_NUMBER CH4102K6E00
J 0
(-1525 4975);
DISPLAY 0.978723 (-1525 4975);
DISPLAY INVISIBLE (-1525 4975);
FORCEADD Q_CAP..1
(-1300 5125);
FORCEPROP 1 LAST LOCATION C619
J 0
(-1250 5225);
DISPLAY 0.978723 (-1250 5225);
PAINT WHITE (-1250 5225);
FORCEPROP 0 LAST $SEC 1
J 0
(-1250 5275);
DISPLAY 0.680851 (-1250 5275);
PAINT MONO (-1250 5275);
DISPLAY INVISIBLE (-1250 5275);
FORCEPROP 0 LAST CDS_SEC 1
J 0
(-1250 5275);
DISPLAY 0.680851 (-1250 5275);
DISPLAY INVISIBLE (-1250 5275);
FORCEPROP 1 LASTPIN (-1300 5225) $PN 1
J 0
(-1290 5205);
DISPLAY 0.787234 (-1290 5205);
PAINT MONO (-1290 5205);
FORCEPROP 1 LASTPIN (-1300 5025) $PN 2
J 0
(-1290 5005);
DISPLAY 0.787234 (-1290 5005);
PAINT MONO (-1290 5005);
FORCEPROP 1 LAST VOLTAGE 10V
J 0
(-1250 5125);
DISPLAY 0.638298 (-1250 5125);
FORCEPROP 1 LAST MATERIAL X7S
J 0
(-1250 5025);
DISPLAY 0.638298 (-1250 5025);
FORCEPROP 1 LAST PACK_TYPE C0201
J 0
(-1250 4975);
DISPLAY 0.638298 (-1250 4975);
FORCEPROP 1 LAST VALUE 0.1UF
J 0
(-1250 5175);
DISPLAY 0.638298 (-1250 5175);
FORCEPROP 1 LAST TOLERANCE 10%
J 0
(-1250 5075);
DISPLAY 0.638298 (-1250 5075);
FORCEPROP 2 LAST CDS_LIB pure_quanta
J 0
(-1300 5125);
DISPLAY INVISIBLE (-1300 5125);
FORCEPROP 1 LAST PATH I84
J 0
(-1250 5275);
DISPLAY 0.978723 (-1250 5275);
PAINT WHITE (-1250 5275);
DISPLAY INVISIBLE (-1250 5275);
FORCEPROP 1 LAST PART_NUMBER CH4102K6E00
J 0
(-1250 4975);
DISPLAY 0.978723 (-1250 4975);
DISPLAY INVISIBLE (-1250 4975);
FORCEADD Q_CAP..1
(-2075 1950);
FORCEPROP 1 LAST LOCATION C614
J 0
(-2025 2050);
DISPLAY 0.978723 (-2025 2050);
PAINT WHITE (-2025 2050);
FORCEPROP 0 LAST $SEC 1
J 0
(-2025 2100);
DISPLAY 0.680851 (-2025 2100);
PAINT MONO (-2025 2100);
DISPLAY INVISIBLE (-2025 2100);
FORCEPROP 0 LAST CDS_SEC 1
J 0
(-2025 2100);
DISPLAY 0.680851 (-2025 2100);
DISPLAY INVISIBLE (-2025 2100);
FORCEPROP 1 LASTPIN (-2075 2050) $PN 1
J 0
(-2065 2030);
DISPLAY 0.787234 (-2065 2030);
PAINT MONO (-2065 2030);
FORCEPROP 1 LASTPIN (-2075 1850) $PN 2
J 0
(-2065 1830);
DISPLAY 0.787234 (-2065 1830);
PAINT MONO (-2065 1830);
FORCEPROP 1 LAST VALUE 0.1UF
J 0
(-2025 2000);
DISPLAY 0.638298 (-2025 2000);
FORCEPROP 1 LAST PACK_TYPE C0201
J 0
(-2025 1800);
DISPLAY 0.638298 (-2025 1800);
FORCEPROP 1 LAST TOLERANCE 10%
J 0
(-2025 1900);
DISPLAY 0.638298 (-2025 1900);
FORCEPROP 1 LAST MATERIAL X7S
J 0
(-2025 1850);
DISPLAY 0.638298 (-2025 1850);
FORCEPROP 1 LAST VOLTAGE 10V
J 0
(-2025 1950);
DISPLAY 0.638298 (-2025 1950);
FORCEPROP 2 LAST CDS_LIB pure_quanta
J 0
(-2075 1950);
DISPLAY INVISIBLE (-2075 1950);
FORCEPROP 1 LAST PATH I85
J 0
(-2025 2100);
DISPLAY 0.978723 (-2025 2100);
PAINT WHITE (-2025 2100);
DISPLAY INVISIBLE (-2025 2100);
FORCEPROP 1 LAST PART_NUMBER CH4102K6E00
J 0
(-2025 1800);
DISPLAY 0.978723 (-2025 1800);
DISPLAY INVISIBLE (-2025 1800);
FORCEADD Q_CAP..1
(-2475 2625);
FORCEPROP 1 LAST LOCATION C622
J 0
(-2425 2725);
DISPLAY 0.978723 (-2425 2725);
PAINT WHITE (-2425 2725);
FORCEPROP 0 LAST $SEC 1
J 0
(-2425 2775);
DISPLAY 0.680851 (-2425 2775);
PAINT MONO (-2425 2775);
DISPLAY INVISIBLE (-2425 2775);
FORCEPROP 0 LAST CDS_SEC 1
J 0
(-2425 2775);
DISPLAY 0.680851 (-2425 2775);
DISPLAY INVISIBLE (-2425 2775);
FORCEPROP 1 LASTPIN (-2475 2725) $PN 1
J 0
(-2465 2705);
DISPLAY 0.787234 (-2465 2705);
PAINT MONO (-2465 2705);
FORCEPROP 1 LASTPIN (-2475 2525) $PN 2
J 0
(-2465 2505);
DISPLAY 0.787234 (-2465 2505);
PAINT MONO (-2465 2505);
FORCEPROP 1 LAST PACK_TYPE 0201
J 0
(-2425 2475);
DISPLAY 0.510638 (-2425 2475);
FORCEPROP 1 LAST VALUE 1UF
J 0
(-2425 2675);
DISPLAY 0.510638 (-2425 2675);
FORCEPROP 1 LAST VOLTAGE 4V
J 0
(-2425 2625);
DISPLAY 0.510638 (-2425 2625);
FORCEPROP 1 LAST TOLERANCE 20%
J 0
(-2425 2575);
DISPLAY 0.510638 (-2425 2575);
FORCEPROP 1 LAST MATERIAL X6S
J 0
(-2425 2525);
DISPLAY 0.510638 (-2425 2525);
FORCEPROP 2 LAST CDS_LIB pure_quanta
J 0
(-2475 2625);
DISPLAY INVISIBLE (-2475 2625);
FORCEPROP 1 LAST PATH I86
J 0
(-2425 2775);
DISPLAY 0.978723 (-2425 2775);
PAINT WHITE (-2425 2775);
DISPLAY INVISIBLE (-2425 2775);
FORCEPROP 1 LAST PART_NUMBER CH-10KMEE00
J 0
(-2425 2475);
DISPLAY 0.510638 (-2425 2475);
DISPLAY INVISIBLE (-2425 2475);
FORCEADD Q_CAP..1
(-2725 3275);
FORCEPROP 1 LAST LOCATION C652
J 0
(-2675 3375);
DISPLAY 0.978723 (-2675 3375);
PAINT WHITE (-2675 3375);
FORCEPROP 0 LAST $SEC 1
J 0
(-2675 3425);
DISPLAY 0.680851 (-2675 3425);
PAINT MONO (-2675 3425);
DISPLAY INVISIBLE (-2675 3425);
FORCEPROP 0 LAST CDS_SEC 1
J 0
(-2675 3425);
DISPLAY 0.680851 (-2675 3425);
DISPLAY INVISIBLE (-2675 3425);
FORCEPROP 1 LASTPIN (-2725 3375) $PN 1
J 0
(-2715 3355);
DISPLAY 0.787234 (-2715 3355);
PAINT MONO (-2715 3355);
FORCEPROP 1 LASTPIN (-2725 3175) $PN 2
J 0
(-2715 3155);
DISPLAY 0.787234 (-2715 3155);
PAINT MONO (-2715 3155);
FORCEPROP 1 LAST VOLTAGE 6.3V
J 0
(-2675 3275);
DISPLAY 0.510638 (-2675 3275);
FORCEPROP 1 LAST PACK_TYPE 0402
J 0
(-2675 3125);
DISPLAY 0.510638 (-2675 3125);
FORCEPROP 1 LAST VALUE 4.7UF
J 0
(-2675 3325);
DISPLAY 0.510638 (-2675 3325);
FORCEPROP 1 LAST TOLERANCE 20%
J 0
(-2675 3225);
DISPLAY 0.510638 (-2675 3225);
FORCEPROP 1 LAST MATERIAL X6S
J 0
(-2675 3175);
DISPLAY 0.510638 (-2675 3175);
FORCEPROP 2 LAST CDS_LIB pure_quanta
J 0
(-2725 3275);
DISPLAY INVISIBLE (-2725 3275);
FORCEPROP 1 LAST PATH I87
J 0
(-2675 3425);
DISPLAY 0.978723 (-2675 3425);
PAINT WHITE (-2675 3425);
DISPLAY INVISIBLE (-2675 3425);
FORCEPROP 1 LAST PART_NUMBER CH5471MEB01
J 0
(-2675 3125);
DISPLAY 0.978723 (-2675 3125);
DISPLAY INVISIBLE (-2675 3125);
FORCEADD Q_INDUCTOR..1
R 3
(-8400 3825);
FORCEPROP 1 LAST LOCATION L28
R 1
J 2
(-8550 3950);
DISPLAY 0.574468 (-8550 3950);
PAINT GREEN (-8550 3950);
FORCEPROP 0 LAST $SEC 1
R 1
J 0
(-8375 3950);
DISPLAY 0.680851 (-8375 3950);
PAINT MONO (-8375 3950);
DISPLAY INVISIBLE (-8375 3950);
FORCEPROP 0 LAST CDS_SEC 1
R 1
J 0
(-8375 3950);
DISPLAY 0.680851 (-8375 3950);
DISPLAY INVISIBLE (-8375 3950);
FORCEPROP 0 LASTPIN (-8375 3925) $PN 1
R 1
J 0
(-8385 3935);
DISPLAY 0.680851 (-8385 3935);
PAINT MONO (-8385 3935);
FORCEPROP 0 LASTPIN (-8375 3725) $PN 2
R 1
J 2
(-8385 3715);
DISPLAY 0.680851 (-8385 3715);
PAINT MONO (-8385 3715);
FORCEPROP 1 LAST MATERIAL IND
R 1
J 2
(-8455 3950);
DISPLAY 0.574468 (-8455 3950);
PAINT GREEN (-8455 3950);
FORCEPROP 2 LAST PACK_TYPE SMLF
R 1
J 2
(-8600 3950);
DISPLAY 0.553191 (-8600 3950);
FORCEPROP 2 LAST VALUE BLM15PD121SN1D/1300MA
R 1
J 2
(-8650 3950);
DISPLAY 0.553191 (-8650 3950);
FORCEPROP 2 LAST CDS_LIB pure_quanta
R 1
J 2
(-8400 3825);
DISPLAY INVISIBLE (-8400 3825);
FORCEPROP 1 LAST NEEDS_NO_SIZE TRUE
R 1
J 2
(-8400 3825);
DISPLAY 0.468085 (-8400 3825);
PAINT GREEN (-8400 3825);
DISPLAY INVISIBLE (-8400 3825);
FORCEPROP 1 LAST PATH I88
R 1
J 2
(-8455 3750);
DISPLAY 0.723404 (-8455 3750);
PAINT GREEN (-8455 3750);
DISPLAY INVISIBLE (-8455 3750);
FORCEPROP 1 LAST PART_NUMBER CX5PD121000
R 1
J 2
(-8500 3950);
DISPLAY 0.574468 (-8500 3950);
PAINT GREEN (-8500 3950);
DISPLAY INVISIBLE (-8500 3950);
FORCEADD Q_RES..2
(-8275 3800);
FORCEPROP 1 LAST LOCATION R1008
J 0
(-8230 3925);
DISPLAY 0.808511 (-8230 3925);
FORCEPROP 0 LAST $SEC 1
J 0
(-8225 3975);
DISPLAY 0.680851 (-8225 3975);
PAINT MONO (-8225 3975);
DISPLAY INVISIBLE (-8225 3975);
FORCEPROP 0 LAST CDS_SEC 1
J 0
(-8225 3975);
DISPLAY 0.680851 (-8225 3975);
DISPLAY INVISIBLE (-8225 3975);
FORCEPROP 1 LASTPIN (-8275 3900) $PN 1
J 0
(-8270 3862);
DISPLAY 0.787234 (-8270 3862);
PAINT MONO (-8270 3862);
FORCEPROP 1 LASTPIN (-8275 3700) $PN 2
J 0
(-8270 3710);
DISPLAY 0.787234 (-8270 3710);
PAINT MONO (-8270 3710);
FORCEPROP 1 LAST TOLERANCE 5%
J 0
(-8230 3825);
DISPLAY 0.638298 (-8230 3825);
FORCEPROP 1 LAST VALUE 0
J 0
(-8230 3875);
DISPLAY 0.638298 (-8230 3875);
FORCEPROP 1 LAST WATTAGE 1/16W
J 0
(-8235 3775);
DISPLAY 0.638298 (-8235 3775);
FORCEPROP 1 LAST MATERIAL EMPTY
J 0
(-8235 3725);
DISPLAY 0.638298 (-8235 3725);
PAINT RED (-8235 3725);
FORCEPROP 1 LAST PACK_TYPE 0402LF
J 0
(-8235 3625);
DISPLAY 0.638298 (-8235 3625);
FORCEPROP 2 LAST CDS_LIB pure_quanta
J 0
(-8275 3800);
DISPLAY INVISIBLE (-8275 3800);
FORCEPROP 1 LAST PATH I89
J 0
(-8225 3975);
DISPLAY 0.978723 (-8225 3975);
PAINT WHITE (-8225 3975);
DISPLAY INVISIBLE (-8225 3975);
FORCEPROP 1 LAST PART_NUMBER CS00002JB13
J 0
(-8235 3675);
DISPLAY 0.638298 (-8235 3675);
DISPLAY INVISIBLE (-8235 3675);
FORCEADD UNIVERSAL_GND..1
(-6325 3575);
FORCEPROP 3 LASTPIN (-6325 3625) SIG_NAME GND\g
J 0
(-6315 3635);
DISPLAY 0.659574 (-6315 3635);
PAINT MONO (-6315 3635);
DISPLAY INVISIBLE (-6315 3635);
FORCEPROP 2 LAST CDS_LIB pure_quanta_power
J 0
(-6325 3575);
DISPLAY INVISIBLE (-6325 3575);
FORCEPROP 1 LAST HDL_POWER GND
J 1
(-6300 3500);
DISPLAY 0.872340 (-6300 3500);
PAINT GREEN (-6300 3500);
DISPLAY INVISIBLE (-6300 3500);
FORCEPROP 1 LAST PATH I9
J 0
(-6250 3575);
DISPLAY 0.872340 (-6250 3575);
PAINT AQUA (-6250 3575);
DISPLAY INVISIBLE (-6250 3575);
FORCEADD Q_CAP..1
(-2950 850);
FORCEPROP 1 LAST LOCATION C621
J 0
(-2900 950);
DISPLAY 0.978723 (-2900 950);
PAINT WHITE (-2900 950);
FORCEPROP 0 LAST $SEC 1
J 0
(-2900 1000);
DISPLAY 0.680851 (-2900 1000);
PAINT MONO (-2900 1000);
DISPLAY INVISIBLE (-2900 1000);
FORCEPROP 0 LAST CDS_SEC 1
J 0
(-2900 1000);
DISPLAY 0.680851 (-2900 1000);
DISPLAY INVISIBLE (-2900 1000);
FORCEPROP 1 LASTPIN (-2950 950) $PN 1
J 0
(-2940 930);
DISPLAY 0.787234 (-2940 930);
PAINT MONO (-2940 930);
FORCEPROP 1 LASTPIN (-2950 750) $PN 2
J 0
(-2940 730);
DISPLAY 0.787234 (-2940 730);
PAINT MONO (-2940 730);
FORCEPROP 1 LAST TOLERANCE 20%
J 0
(-2900 800);
DISPLAY 0.510638 (-2900 800);
FORCEPROP 1 LAST MATERIAL X6S
J 0
(-2900 750);
DISPLAY 0.510638 (-2900 750);
FORCEPROP 1 LAST PACK_TYPE 0201
J 0
(-2900 700);
DISPLAY 0.510638 (-2900 700);
FORCEPROP 1 LAST VOLTAGE 4V
J 0
(-2900 850);
DISPLAY 0.510638 (-2900 850);
FORCEPROP 1 LAST VALUE 1UF
J 0
(-2900 900);
DISPLAY 0.510638 (-2900 900);
FORCEPROP 2 LAST CDS_LIB pure_quanta
J 0
(-2950 850);
DISPLAY INVISIBLE (-2950 850);
FORCEPROP 1 LAST PATH I90
J 0
(-2900 1000);
DISPLAY 0.978723 (-2900 1000);
PAINT WHITE (-2900 1000);
DISPLAY INVISIBLE (-2900 1000);
FORCEPROP 1 LAST PART_NUMBER CH-10KMEE00
J 0
(-2900 700);
DISPLAY 0.510638 (-2900 700);
DISPLAY INVISIBLE (-2900 700);
FORCEADD Q_CAP..1
(-2400 850);
FORCEPROP 1 LAST LOCATION C624
J 0
(-2350 950);
DISPLAY 0.978723 (-2350 950);
PAINT WHITE (-2350 950);
FORCEPROP 0 LAST $SEC 1
J 0
(-2350 1000);
DISPLAY 0.680851 (-2350 1000);
PAINT MONO (-2350 1000);
DISPLAY INVISIBLE (-2350 1000);
FORCEPROP 0 LAST CDS_SEC 1
J 0
(-2350 1000);
DISPLAY 0.680851 (-2350 1000);
DISPLAY INVISIBLE (-2350 1000);
FORCEPROP 1 LASTPIN (-2400 950) $PN 1
J 0
(-2390 930);
DISPLAY 0.787234 (-2390 930);
PAINT MONO (-2390 930);
FORCEPROP 1 LASTPIN (-2400 750) $PN 2
J 0
(-2390 730);
DISPLAY 0.787234 (-2390 730);
PAINT MONO (-2390 730);
FORCEPROP 1 LAST TOLERANCE 20%
J 0
(-2350 800);
DISPLAY 0.510638 (-2350 800);
FORCEPROP 1 LAST MATERIAL X6S
J 0
(-2350 750);
DISPLAY 0.510638 (-2350 750);
FORCEPROP 1 LAST PACK_TYPE 0201
J 0
(-2350 700);
DISPLAY 0.510638 (-2350 700);
FORCEPROP 1 LAST VOLTAGE 4V
J 0
(-2350 850);
DISPLAY 0.510638 (-2350 850);
FORCEPROP 1 LAST VALUE 1UF
J 0
(-2350 900);
DISPLAY 0.510638 (-2350 900);
FORCEPROP 2 LAST CDS_LIB pure_quanta
J 0
(-2400 850);
DISPLAY INVISIBLE (-2400 850);
FORCEPROP 1 LAST PATH I91
J 0
(-2350 1000);
DISPLAY 0.978723 (-2350 1000);
PAINT WHITE (-2350 1000);
DISPLAY INVISIBLE (-2350 1000);
FORCEPROP 1 LAST PART_NUMBER CH-10KMEE00
J 0
(-2350 700);
DISPLAY 0.510638 (-2350 700);
DISPLAY INVISIBLE (-2350 700);
FORCEADD Q_CAP..1
(-1975 2625);
FORCEPROP 1 LAST LOCATION C658
J 0
(-1925 2725);
DISPLAY 0.978723 (-1925 2725);
PAINT WHITE (-1925 2725);
FORCEPROP 0 LAST $SEC 1
J 0
(-1925 2775);
DISPLAY 0.680851 (-1925 2775);
PAINT MONO (-1925 2775);
DISPLAY INVISIBLE (-1925 2775);
FORCEPROP 0 LAST CDS_SEC 1
J 0
(-1925 2775);
DISPLAY 0.680851 (-1925 2775);
DISPLAY INVISIBLE (-1925 2775);
FORCEPROP 1 LASTPIN (-1975 2725) $PN 1
J 0
(-1965 2705);
DISPLAY 0.787234 (-1965 2705);
PAINT MONO (-1965 2705);
FORCEPROP 1 LASTPIN (-1975 2525) $PN 2
J 0
(-1965 2505);
DISPLAY 0.787234 (-1965 2505);
PAINT MONO (-1965 2505);
FORCEPROP 1 LAST TOLERANCE 10%
J 0
(-1925 2575);
DISPLAY 0.638298 (-1925 2575);
FORCEPROP 1 LAST VOLTAGE 10V
J 0
(-1925 2625);
DISPLAY 0.638298 (-1925 2625);
FORCEPROP 1 LAST PACK_TYPE C0201
J 0
(-1925 2475);
DISPLAY 0.638298 (-1925 2475);
FORCEPROP 1 LAST MATERIAL X7S
J 0
(-1925 2525);
DISPLAY 0.638298 (-1925 2525);
FORCEPROP 1 LAST VALUE 0.1UF
J 0
(-1925 2675);
DISPLAY 0.638298 (-1925 2675);
FORCEPROP 2 LAST CDS_LIB pure_quanta
J 0
(-1975 2625);
DISPLAY INVISIBLE (-1975 2625);
FORCEPROP 1 LAST PATH I92
J 0
(-1925 2775);
DISPLAY 0.978723 (-1925 2775);
PAINT WHITE (-1925 2775);
DISPLAY INVISIBLE (-1925 2775);
FORCEPROP 1 LAST PART_NUMBER CH4102K6E00
J 0
(-1925 2475);
DISPLAY 0.978723 (-1925 2475);
DISPLAY INVISIBLE (-1925 2475);
FORCEADD Q_CAP..1
(-1700 2625);
FORCEPROP 1 LAST LOCATION C659
J 0
(-1650 2725);
DISPLAY 0.978723 (-1650 2725);
PAINT WHITE (-1650 2725);
FORCEPROP 0 LAST $SEC 1
J 0
(-1650 2775);
DISPLAY 0.680851 (-1650 2775);
PAINT MONO (-1650 2775);
DISPLAY INVISIBLE (-1650 2775);
FORCEPROP 0 LAST CDS_SEC 1
J 0
(-1650 2775);
DISPLAY 0.680851 (-1650 2775);
DISPLAY INVISIBLE (-1650 2775);
FORCEPROP 1 LASTPIN (-1700 2725) $PN 1
J 0
(-1690 2705);
DISPLAY 0.787234 (-1690 2705);
PAINT MONO (-1690 2705);
FORCEPROP 1 LASTPIN (-1700 2525) $PN 2
J 0
(-1690 2505);
DISPLAY 0.787234 (-1690 2505);
PAINT MONO (-1690 2505);
FORCEPROP 1 LAST VOLTAGE 10V
J 0
(-1650 2625);
DISPLAY 0.638298 (-1650 2625);
FORCEPROP 1 LAST VALUE 0.1UF
J 0
(-1650 2675);
DISPLAY 0.638298 (-1650 2675);
FORCEPROP 1 LAST PACK_TYPE C0201
J 0
(-1650 2475);
DISPLAY 0.638298 (-1650 2475);
FORCEPROP 1 LAST MATERIAL X7S
J 0
(-1650 2525);
DISPLAY 0.638298 (-1650 2525);
FORCEPROP 1 LAST TOLERANCE 10%
J 0
(-1650 2575);
DISPLAY 0.638298 (-1650 2575);
FORCEPROP 2 LAST CDS_LIB pure_quanta
J 0
(-1700 2625);
DISPLAY INVISIBLE (-1700 2625);
FORCEPROP 1 LAST PATH I93
J 0
(-1650 2775);
DISPLAY 0.978723 (-1650 2775);
PAINT WHITE (-1650 2775);
DISPLAY INVISIBLE (-1650 2775);
FORCEPROP 1 LAST PART_NUMBER CH4102K6E00
J 0
(-1650 2475);
DISPLAY 0.978723 (-1650 2475);
DISPLAY INVISIBLE (-1650 2475);
FORCEADD Q_CAP..1
(-1825 3275);
FORCEPROP 1 LAST LOCATION C660
J 0
(-1775 3375);
DISPLAY 0.978723 (-1775 3375);
PAINT WHITE (-1775 3375);
FORCEPROP 0 LAST $SEC 1
J 0
(-1775 3425);
DISPLAY 0.680851 (-1775 3425);
PAINT MONO (-1775 3425);
DISPLAY INVISIBLE (-1775 3425);
FORCEPROP 0 LAST CDS_SEC 1
J 0
(-1775 3425);
DISPLAY 0.680851 (-1775 3425);
DISPLAY INVISIBLE (-1775 3425);
FORCEPROP 1 LASTPIN (-1825 3375) $PN 1
J 0
(-1815 3355);
DISPLAY 0.787234 (-1815 3355);
PAINT MONO (-1815 3355);
FORCEPROP 1 LASTPIN (-1825 3175) $PN 2
J 0
(-1815 3155);
DISPLAY 0.787234 (-1815 3155);
PAINT MONO (-1815 3155);
FORCEPROP 1 LAST VALUE 1UF
J 0
(-1775 3325);
DISPLAY 0.510638 (-1775 3325);
FORCEPROP 1 LAST VOLTAGE 4V
J 0
(-1775 3275);
DISPLAY 0.510638 (-1775 3275);
FORCEPROP 1 LAST TOLERANCE 20%
J 0
(-1775 3225);
DISPLAY 0.510638 (-1775 3225);
FORCEPROP 1 LAST MATERIAL X6S
J 0
(-1775 3175);
DISPLAY 0.510638 (-1775 3175);
FORCEPROP 1 LAST PACK_TYPE 0201
J 0
(-1775 3125);
DISPLAY 0.510638 (-1775 3125);
FORCEPROP 2 LAST CDS_LIB pure_quanta
J 0
(-1825 3275);
DISPLAY INVISIBLE (-1825 3275);
FORCEPROP 1 LAST PATH I94
J 0
(-1775 3425);
DISPLAY 0.978723 (-1775 3425);
PAINT WHITE (-1775 3425);
DISPLAY INVISIBLE (-1775 3425);
FORCEPROP 1 LAST PART_NUMBER CH-10KMEE00
J 0
(-1775 3125);
DISPLAY 0.510638 (-1775 3125);
DISPLAY INVISIBLE (-1775 3125);
FORCEADD Q_CAPP..1
(-1275 1950);
FORCEPROP 1 LAST LOCATION C7011
J 0
(-1225 2050);
DISPLAY 0.787234 (-1225 2050);
FORCEPROP 0 LAST $SEC 1
J 0
(-1225 2100);
DISPLAY 0.680851 (-1225 2100);
PAINT MONO (-1225 2100);
DISPLAY INVISIBLE (-1225 2100);
FORCEPROP 0 LAST CDS_SEC 1
J 0
(-1225 2100);
DISPLAY 0.680851 (-1225 2100);
DISPLAY INVISIBLE (-1225 2100);
FORCEPROP 1 LASTPIN (-1275 2050) $PN 1
J 0
(-1265 2035);
DISPLAY 0.787234 (-1265 2035);
PAINT MONO (-1265 2035);
FORCEPROP 1 LASTPIN (-1275 1850) $PN 2
J 0
(-1265 1835);
DISPLAY 0.787234 (-1265 1835);
PAINT MONO (-1265 1835);
FORCEPROP 1 LAST MATERIAL SPCAP
J 0
(-1225 1850);
DISPLAY 0.510638 (-1225 1850);
FORCEPROP 1 LAST VOLTAGE 2.5V
J 0
(-1225 1900);
DISPLAY 0.510638 (-1225 1900);
FORCEPROP 1 LAST PACK_TYPE SMLF
J 0
(-1225 1800);
DISPLAY 0.510638 (-1225 1800);
FORCEPROP 1 LAST TOLERANCE 20%
J 0
(-1225 1950);
DISPLAY 0.510638 (-1225 1950);
FORCEPROP 1 LAST VALUE 470UF
J 0
(-1225 2000);
DISPLAY 0.510638 (-1225 2000);
FORCEPROP 2 LAST CDS_LIB pure_quanta
J 0
(-1275 1950);
DISPLAY INVISIBLE (-1275 1950);
FORCEPROP 1 LAST PATH I95
J 0
(-1225 2100);
DISPLAY 0.978723 (-1225 2100);
DISPLAY INVISIBLE (-1225 2100);
FORCEPROP 1 LAST PART_NUMBER CH747LM8818
J 0
(-1225 1750);
DISPLAY 0.404255 (-1225 1750);
DISPLAY INVISIBLE (-1225 1750);
FORCEADD Q_CAPP..1
(-975 1950);
FORCEPROP 1 LAST LOCATION C7012
J 0
(-925 2050);
DISPLAY 0.787234 (-925 2050);
FORCEPROP 0 LAST $SEC 1
J 0
(-925 2100);
DISPLAY 0.680851 (-925 2100);
PAINT MONO (-925 2100);
DISPLAY INVISIBLE (-925 2100);
FORCEPROP 0 LAST CDS_SEC 1
J 0
(-925 2100);
DISPLAY 0.680851 (-925 2100);
DISPLAY INVISIBLE (-925 2100);
FORCEPROP 1 LASTPIN (-975 2050) $PN 1
J 0
(-965 2035);
DISPLAY 0.787234 (-965 2035);
PAINT MONO (-965 2035);
FORCEPROP 1 LASTPIN (-975 1850) $PN 2
J 0
(-965 1835);
DISPLAY 0.787234 (-965 1835);
PAINT MONO (-965 1835);
FORCEPROP 1 LAST PACK_TYPE SMLF
J 0
(-925 1800);
DISPLAY 0.510638 (-925 1800);
FORCEPROP 1 LAST TOLERANCE 20%
J 0
(-925 1950);
DISPLAY 0.510638 (-925 1950);
FORCEPROP 1 LAST VOLTAGE 2.5V
J 0
(-925 1900);
DISPLAY 0.510638 (-925 1900);
FORCEPROP 1 LAST MATERIAL SPCAP
J 0
(-925 1850);
DISPLAY 0.510638 (-925 1850);
FORCEPROP 1 LAST VALUE 470UF
J 0
(-925 2000);
DISPLAY 0.510638 (-925 2000);
FORCEPROP 2 LAST CDS_LIB pure_quanta
J 0
(-975 1950);
DISPLAY INVISIBLE (-975 1950);
FORCEPROP 1 LAST PATH I96
J 0
(-925 2100);
DISPLAY 0.978723 (-925 2100);
DISPLAY INVISIBLE (-925 2100);
FORCEPROP 1 LAST PART_NUMBER CH747LM8818
J 0
(-925 1750);
DISPLAY 0.404255 (-925 1750);
DISPLAY INVISIBLE (-925 1750);
FORCEADD Q_CAP..1
(-675 1950);
FORCEPROP 1 LAST LOCATION C7013
J 0
(-625 2050);
DISPLAY 0.638298 (-625 2050);
FORCEPROP 0 LAST $SEC 1
J 0
(-625 2100);
DISPLAY 0.680851 (-625 2100);
PAINT MONO (-625 2100);
DISPLAY INVISIBLE (-625 2100);
FORCEPROP 0 LAST CDS_SEC 1
J 0
(-625 2100);
DISPLAY 0.680851 (-625 2100);
DISPLAY INVISIBLE (-625 2100);
FORCEPROP 1 LASTPIN (-675 2050) $PN 1
J 0
(-665 2030);
DISPLAY 0.787234 (-665 2030);
PAINT MONO (-665 2030);
FORCEPROP 1 LASTPIN (-675 1850) $PN 2
J 0
(-665 1830);
DISPLAY 0.787234 (-665 1830);
PAINT MONO (-665 1830);
FORCEPROP 1 LAST TOLERANCE 20%
J 0
(-625 1900);
DISPLAY 0.638298 (-625 1900);
FORCEPROP 1 LAST VALUE 100UF
J 0
(-625 2000);
DISPLAY 0.638298 (-625 2000);
FORCEPROP 1 LAST VOLTAGE 4V
J 0
(-625 1950);
DISPLAY 0.638298 (-625 1950);
FORCEPROP 1 LAST MATERIAL X6S
J 0
(-625 1850);
DISPLAY 0.638298 (-625 1850);
FORCEPROP 1 LAST PACK_TYPE C0805
J 0
(-625 1750);
DISPLAY 0.638298 (-625 1750);
FORCEPROP 2 LAST CDS_LIB pure_quanta
J 0
(-675 1950);
DISPLAY INVISIBLE (-675 1950);
FORCEPROP 1 LAST PATH I97
J 0
(-625 2100);
DISPLAY 0.978723 (-625 2100);
PAINT WHITE (-625 2100);
DISPLAY INVISIBLE (-625 2100);
FORCEPROP 1 LAST PART_NUMBER CH710KMEA01
J 0
(-625 1800);
DISPLAY 0.638298 (-625 1800);
DISPLAY INVISIBLE (-625 1800);
FORCEADD DNS..2
(-8175 3775);
PAINT RED (-8175 3775);
FORCEPROP 2 LAST CDS_LIB mstr_misc
J 0
(-8175 3775);
DISPLAY INVISIBLE (-8175 3775);
FORCEPROP 1 LAST COMMENT_BODY TRUE
J 0
(-8175 3775);
DISPLAY INVISIBLE (-8175 3775);
FORCEADD QUANTA_TITLE_BLOCK_C..1
(0 0);
FORCEPROP 0 LAST CDS_CON_LAST_MODIFIED Thu Sep 14 16:13:08 2023
J 0
(-1885 15);
DISPLAY INVISIBLE (-1885 15);
FORCEPROP 1 LAST CUSTOM_TXT_CDS <CON_LAST_MODIFIED>
J 0
(-1885 15);
DISPLAY 0.978723 (-1885 15);
FORCEPROP 2 LAST CUSTOM_TXT_CDS <XR_PAGE_TITLE>
J 0
(-7890 5250);
DISPLAY 0.638298 (-7890 5250);
PAINT PINK (-7890 5250);
DISPLAY INVISIBLE (-7890 5250);
FORCEPROP 1 LAST CUSTOM_TXT_CDS <NAME_2>
J 0
(-3175 50);
FORCEPROP 1 LAST CUSTOM_TXT_CDS <NAME_1>
J 0
(-3175 175);
FORCEPROP 1 LAST CUSTOM_TXT_CDS <Q_NUMBER>
J 0
(-1403 103);
DISPLAY 1.212766 (-1403 103);
FORCEPROP 1 LAST CUSTOM_TXT_CDS <Q_PROJ>
J 0
(-2382 102);
DISPLAY 1.212766 (-2382 102);
FORCEPROP 1 LAST CUSTOM_TXT_CDS <Q_REV>
J 0
(-184 103);
DISPLAY 1.212766 (-184 103);
FORCEPROP 1 LAST CUSTOM_TXT_CDS <CON_PAGE_NUM> OF <CON_TOTAL_PAGES>
J 0
(-446 18);
DISPLAY 0.978723 (-446 18);
FORCEPROP 1 LAST Q_TITLE RETIMER_CPU0_P1 DECAPS(8)
J 0
(-9366 26);
DISPLAY 2.446809 (-9366 26);
PAINT GREEN (-9366 26);
FORCEPROP 2 LAST PAGE_BORDER TRUE
J 0
(-7890 5250);
DISPLAY 0.638298 (-7890 5250);
PAINT PINK (-7890 5250);
DISPLAY INVISIBLE (-7890 5250);
FORCEPROP 1 LAST CDS_LMAN_SYM_OUTLINE -9475,6775,100,-125
J 0
(0 0);
DISPLAY 0.468085 (0 0);
PAINT GREEN (0 0);
DISPLAY INVISIBLE (0 0);
FORCEPROP 2 LAST CDS_LIB pure_quanta
J 0
(0 0);
DISPLAY INVISIBLE (0 0);
FORCEPROP 2 LAST CDS_XR_PAGE_TITLE CR-291 : @T6G_MB_LIB.T6G(SCH_1):PAGE291
J 0
(-7890 5250);
DISPLAY 0.638298 (-7890 5250);
PAINT PINK (-7890 5250);
DISPLAY INVISIBLE (-7890 5250);
FORCEPROP 1 LAST Q_DEPT BU9
J 1
(-3763 49);
DISPLAY 1.957447 (-3763 49);
PAINT GREEN (-3763 49);
DISPLAY INVISIBLE (-3763 49);
FORCEPROP 1 LAST COMMENT_BODY TRUE
J 0
(12 -13);
DISPLAY 0.978723 (12 -13);
PAINT GREEN (12 -13);
DISPLAY INVISIBLE (12 -13);
FORCEADD DNS..2
(-4525 2450);
PAINT RED (-4525 2450);
FORCEPROP 2 LAST CDS_LIB mstr_misc
J 0
(-4525 2450);
DISPLAY INVISIBLE (-4525 2450);
FORCEPROP 1 LAST COMMENT_BODY TRUE
J 0
(-4525 2450);
DISPLAY INVISIBLE (-4525 2450);
FORCEADD CAD_NOTE..1
(-5275 2150);
FORCEPROP 0 LAST S1 R1010 AND R1011 COLAY
J 0
(-5400 2025);
DISPLAY 0.808511 (-5400 2025);
PAINT WHITE (-5400 2025);
FORCEPROP 2 LAST CDS_LIB pure_quanta_power
J 0
(-5275 2150);
DISPLAY INVISIBLE (-5275 2150);
FORCEPROP 1 LAST COMMENT_BODY TRUE
J 0
(-5250 2250);
DISPLAY 0.978723 (-5250 2250);
DISPLAY INVISIBLE (-5250 2250);
FORCEADD DNS..2
(-7850 3425);
PAINT RED (-7850 3425);
FORCEPROP 2 LAST CDS_LIB mstr_misc
J 0
(-7850 3425);
DISPLAY INVISIBLE (-7850 3425);
FORCEPROP 1 LAST COMMENT_BODY TRUE
J 0
(-7850 3425);
DISPLAY INVISIBLE (-7850 3425);
FORCEADD DNS..2
(-7850 3250);
PAINT RED (-7850 3250);
FORCEPROP 2 LAST CDS_LIB mstr_misc
J 0
(-7850 3250);
DISPLAY INVISIBLE (-7850 3250);
FORCEPROP 1 LAST COMMENT_BODY TRUE
J 0
(-7850 3250);
DISPLAY INVISIBLE (-7850 3250);
FORCEADD CAD_NOTE..1
(-8325 2650);
FORCEPROP 0 LAST S1 L28/R1008 COLAY WITH R1002/R1003
J 0
(-8450 2525);
DISPLAY 0.808511 (-8450 2525);
PAINT WHITE (-8450 2525);
FORCEPROP 2 LAST CDS_LIB pure_quanta_power
J 0
(-8325 2650);
DISPLAY INVISIBLE (-8325 2650);
FORCEPROP 1 LAST COMMENT_BODY TRUE
J 0
(-8300 2750);
DISPLAY 0.978723 (-8300 2750);
DISPLAY INVISIBLE (-8300 2750);
WIRE 16 -1 (-5325 4150)(-5600 4150);
WIRE 16 -1 (-5325 4150)(-5325 4000);
WIRE 16 -1 (-5600 4150)(-5850 4150);
WIRE 16 -1 (-5600 4150)(-5600 4000);
WIRE 16 -1 (-5850 4150)(-6100 4150);
WIRE 16 -1 (-5850 4150)(-5850 4000);
WIRE 16 -1 (-6325 4150)(-6100 4150);
WIRE 16 -1 (-6100 4150)(-6100 4000);
WIRE 16 -1 (-6325 4150)(-6525 4150);
WIRE 16 -1 (-6325 4150)(-6325 4000);
WIRE 16 -1 (-6525 4150)(-6750 4150);
WIRE 16 -1 (-6525 4150)(-6525 4000);
WIRE 16 -1 (-6950 4150)(-6750 4150);
WIRE 16 -1 (-6750 4150)(-6750 4000);
WIRE 16 -1 (-6950 4150)(-7150 4150);
WIRE 16 -1 (-6950 4150)(-6950 4000);
WIRE 16 -1 (-7375 4150)(-7150 4150);
WIRE 16 -1 (-7150 4150)(-7150 4000);
WIRE 16 -1 (-7375 4150)(-7475 4150);
WIRE 16 -1 (-7375 4150)(-7375 4000);
WIRE 16 -1 (-7475 4325)(-7475 4150);
WIRE 16 -1 (-7475 4150)(-7850 4150);
WIRE 16 -1 (-7475 3375)(-7475 4150);
WIRE 16 -1 (-7575 3375)(-7475 3375);
WIRE 16 -1 (-7575 3475)(-7575 3375);
WIRE 16 -1 (-7575 3375)(-7575 3275);
WIRE 16 -1 (-7775 3275)(-7575 3275);
WIRE 16 -1 (-7775 3475)(-7575 3475);
WIRE 16 -1 (-675 2200)(-675 2050);
WIRE 16 -1 (-675 2200)(-975 2200);
WIRE 16 -1 (-975 2050)(-975 2200);
WIRE 16 -1 (-975 2200)(-1275 2200);
WIRE 16 -1 (-1275 2050)(-1275 2200);
WIRE 16 -1 (-1550 2200)(-1275 2200);
WIRE 16 -1 (-1550 2050)(-1550 2200);
WIRE 16 -1 (-1550 2200)(-1800 2200);
WIRE 16 -1 (-1800 2050)(-1800 2200);
WIRE 16 -1 (-2075 2200)(-1800 2200);
WIRE 16 -1 (-2075 2050)(-2075 2200);
WIRE 16 -1 (-2350 2200)(-2075 2200);
WIRE 16 -1 (-2350 2050)(-2350 2200);
WIRE 16 -1 (-2600 2200)(-2350 2200);
WIRE 16 -1 (-2600 2050)(-2600 2200);
WIRE 16 -1 (-2850 2200)(-2600 2200);
WIRE 16 -1 (-2850 2200)(-2850 2050);
WIRE 16 -1 (-3075 2200)(-2850 2200);
WIRE 16 -1 (-3075 2200)(-3075 2050);
WIRE 16 -1 (-3375 2200)(-3075 2200);
WIRE 16 -1 (-3375 2200)(-3375 2050);
WIRE 16 -1 (-3825 2200)(-3375 2200);
WIRE 16 -1 (-3825 2875)(-3825 2200);
WIRE 16 -1 (-3825 2200)(-4000 2200);
WIRE 16 -1 (-3825 3500)(-3825 2875);
WIRE 16 -1 (-3825 2875)(-3650 2875);
WIRE 16 -1 (-3650 2875)(-3425 2875);
WIRE 16 -1 (-3650 2875)(-3650 2750);
WIRE 16 -1 (-3825 4150)(-3825 3500);
WIRE 16 -1 (-3825 3500)(-3650 3500);
WIRE 16 -1 (-3650 3500)(-3425 3500);
WIRE 16 -1 (-3650 3375)(-3650 3500);
WIRE 16 -1 (-3825 4150)(-3650 4150);
WIRE 16 -1 (-3900 4150)(-3825 4150);
WIRE 16 -1 (-3425 2875)(-3175 2875);
WIRE 16 -1 (-3425 2875)(-3425 2750);
WIRE 16 -1 (-3175 2875)(-2950 2875);
WIRE 16 -1 (-3175 2875)(-3175 2750);
WIRE 16 -1 (-3650 4150)(-3425 4150);
WIRE 16 -1 (-3650 4500)(-3650 4150);
WIRE 16 -1 (-3650 4150)(-3650 4000);
WIRE 16 -1 (-3425 3500)(-3200 3500);
WIRE 16 -1 (-3425 3375)(-3425 3500);
WIRE 16 -1 (-3200 3500)(-2975 3500);
WIRE 16 -1 (-3200 3375)(-3200 3500);
WIRE 16 -1 (-3200 4150)(-3425 4150);
WIRE 16 -1 (-3425 4150)(-3425 4000);
WIRE 16 -1 (-2950 2875)(-2700 2875);
WIRE 16 -1 (-2950 2875)(-2950 2750);
WIRE 16 -1 (-2700 2875)(-2475 2875);
WIRE 16 -1 (-2700 2875)(-2700 2750);
WIRE 16 -1 (-2975 4150)(-3200 4150);
WIRE 16 -1 (-3200 4150)(-3200 4000);
WIRE 16 -1 (-2975 3500)(-2725 3500);
WIRE 16 -1 (-2975 3375)(-2975 3500);
WIRE 16 -1 (-2725 3500)(-2500 3500);
WIRE 16 -1 (-2725 3375)(-2725 3500);
WIRE 16 -1 (-2725 4150)(-2975 4150);
WIRE 16 -1 (-2975 4150)(-2975 4000);
WIRE 16 -1 (-2475 2875)(-2250 2875);
WIRE 16 -1 (-2475 2875)(-2475 2725);
WIRE 16 -1 (-2250 2875)(-1975 2875);
WIRE 16 -1 (-2250 2725)(-2250 2875);
WIRE 16 -1 (-2500 4150)(-2725 4150);
WIRE 16 -1 (-2725 4150)(-2725 4000);
WIRE 16 -1 (-2500 3500)(-2275 3500);
WIRE 16 -1 (-2500 3375)(-2500 3500);
WIRE 16 -1 (-2275 3500)(-2050 3500);
WIRE 16 -1 (-2275 3375)(-2275 3500);
WIRE 16 -1 (-2275 4150)(-2500 4150);
WIRE 16 -1 (-2500 4150)(-2500 4000);
WIRE 16 -1 (-1700 2875)(-1975 2875);
WIRE 16 -1 (-1975 2875)(-1975 2725);
WIRE 16 -1 (-1700 2875)(-1700 2725);
WIRE 16 -1 (-2050 4150)(-2275 4150);
WIRE 16 -1 (-2275 4150)(-2275 4000);
WIRE 16 -1 (-2050 3500)(-1825 3500);
WIRE 16 -1 (-2050 3375)(-2050 3500);
WIRE 16 -1 (-1575 3500)(-1825 3500);
WIRE 16 -1 (-1825 3375)(-1825 3500);
WIRE 16 -1 (-1750 4150)(-2050 4150);
WIRE 16 -1 (-2050 4150)(-2050 4000);
WIRE 16 -1 (-1750 4150)(-1450 4150);
WIRE 16 -1 (-1750 4150)(-1750 4000);
WIRE 16 -1 (-1575 3500)(-1575 3375);
WIRE 16 -1 (-1450 4150)(-1450 4000);
WIRE 16 -1 (-3650 3175)(-3650 3050);
WIRE 16 -1 (-3650 3050)(-3425 3050);
WIRE 16 -1 (-3425 3175)(-3425 3050);
WIRE 16 -1 (-3425 3050)(-3200 3050);
WIRE 16 -1 (-3200 3050)(-2975 3050);
WIRE 16 -1 (-3200 3175)(-3200 3050);
WIRE 16 -1 (-2975 3175)(-2975 3050);
WIRE 16 -1 (-2975 3050)(-2725 3050);
WIRE 16 -1 (-2725 3175)(-2725 3050);
WIRE 16 -1 (-2725 3050)(-2500 3050);
WIRE 16 -1 (-2500 3175)(-2500 3050);
WIRE 16 -1 (-2500 3050)(-2275 3050);
WIRE 16 -1 (-2275 3175)(-2275 3050);
WIRE 16 -1 (-2275 3050)(-2050 3050);
WIRE 16 -1 (-2050 3050)(-1825 3050);
WIRE 16 -1 (-2050 3175)(-2050 3050);
WIRE 16 -1 (-1825 3175)(-1825 3050);
WIRE 16 -1 (-1575 3050)(-1825 3050);
WIRE 16 -1 (-1575 3175)(-1575 3050);
WIRE 16 -1 (-1050 3050)(-1575 3050);
WIRE 16 -1 (-1050 3650)(-1050 3050);
WIRE 16 -1 (-1050 3050)(-1050 2325);
WIRE 16 -1 (-1050 2325)(-1700 2325);
WIRE 16 -1 (-1050 2325)(-1050 2275);
WIRE 16 -1 (-1050 3650)(-1450 3650);
WIRE 16 -1 (-1450 3800)(-1450 3650);
WIRE 16 -1 (-1450 3650)(-1750 3650);
WIRE 16 -1 (-1700 2525)(-1700 2325);
WIRE 16 -1 (-1700 2325)(-1975 2325);
WIRE 16 -1 (-1975 2525)(-1975 2325);
WIRE 16 -1 (-2250 2325)(-1975 2325);
WIRE 16 -1 (-1750 3800)(-1750 3650);
WIRE 16 -1 (-1750 3650)(-2050 3650);
WIRE 16 -1 (-2050 3800)(-2050 3650);
WIRE 16 -1 (-2050 3650)(-2275 3650);
WIRE 16 -1 (-2250 2525)(-2250 2325);
WIRE 16 -1 (-2475 2325)(-2250 2325);
WIRE 16 -1 (-2475 2525)(-2475 2325);
WIRE 16 -1 (-2700 2325)(-2475 2325);
WIRE 16 -1 (-2275 3800)(-2275 3650);
WIRE 16 -1 (-2275 3650)(-2500 3650);
WIRE 16 -1 (-2500 3800)(-2500 3650);
WIRE 16 -1 (-2500 3650)(-2725 3650);
WIRE 16 -1 (-2700 2550)(-2700 2325);
WIRE 16 -1 (-2950 2325)(-2700 2325);
WIRE 16 -1 (-2950 2550)(-2950 2325);
WIRE 16 -1 (-3175 2325)(-2950 2325);
WIRE 16 -1 (-2725 3800)(-2725 3650);
WIRE 16 -1 (-2725 3650)(-2975 3650);
WIRE 16 -1 (-2975 3800)(-2975 3650);
WIRE 16 -1 (-3200 3650)(-2975 3650);
WIRE 16 -1 (-3175 2550)(-3175 2325);
WIRE 16 -1 (-3425 2325)(-3175 2325);
WIRE 16 -1 (-3425 2550)(-3425 2325);
WIRE 16 -1 (-3650 2325)(-3425 2325);
WIRE 16 -1 (-3200 3800)(-3200 3650);
WIRE 16 -1 (-3425 3650)(-3200 3650);
WIRE 16 -1 (-3425 3800)(-3425 3650);
WIRE 16 -1 (-3650 3650)(-3425 3650);
WIRE 16 -1 (-3650 2550)(-3650 2325);
WIRE 16 -1 (-3650 3800)(-3650 3650);
WIRE 16 -1 (-1300 5400)(-1300 5225);
WIRE 16 -1 (-1575 5400)(-1300 5400);
WIRE 16 -1 (-1575 5400)(-1575 5225);
WIRE 16 -1 (-1825 5400)(-1575 5400);
WIRE 16 -1 (-1825 5225)(-1825 5400);
WIRE 16 -1 (-2100 5400)(-1825 5400);
WIRE 16 -1 (-2100 5400)(-2100 5225);
WIRE 16 -1 (-2400 5400)(-2100 5400);
WIRE 16 -1 (-2400 5400)(-2400 5250);
WIRE 16 -1 (-2700 5400)(-2400 5400);
WIRE 16 -1 (-2700 5400)(-2700 5250);
WIRE 16 -1 (-3000 5400)(-2700 5400);
WIRE 16 -1 (-3000 5400)(-3000 5250);
WIRE 16 -1 (-3325 5400)(-3000 5400);
WIRE 16 -1 (-3325 5400)(-3325 5275);
WIRE 16 -1 (-3600 5400)(-3325 5400);
WIRE 16 -1 (-3600 5400)(-3600 5275);
WIRE 16 -1 (-4475 5400)(-3600 5400);
WIRE 16 -1 (-4475 5625)(-4475 5400);
WIRE 16 -1 (-4475 4150)(-4475 5400);
WIRE 16 -1 (-4100 4150)(-4475 4150);
WIRE 16 -1 (-4475 4150)(-4475 2575);
WIRE 16 -1 (-1300 5025)(-1300 4850);
WIRE 16 -1 (-1300 4850)(-1375 4850);
WIRE 16 -1 (-1375 4850)(-1575 4850);
WIRE 16 -1 (-1375 4850)(-1375 4775);
WIRE 16 -1 (-1575 5025)(-1575 4850);
WIRE 16 -1 (-1825 4850)(-1575 4850);
WIRE 16 -1 (-1825 5025)(-1825 4850);
WIRE 16 -1 (-2100 4850)(-1825 4850);
WIRE 16 -1 (-2100 5025)(-2100 4850);
WIRE 16 -1 (-2100 4850)(-2400 4850);
WIRE 16 -1 (-2400 5050)(-2400 4850);
WIRE 16 -1 (-2700 4850)(-2400 4850);
WIRE 16 -1 (-2700 5050)(-2700 4850);
WIRE 16 -1 (-3000 4850)(-2700 4850);
WIRE 16 -1 (-3000 5050)(-3000 4850);
WIRE 16 -1 (-3325 4850)(-3000 4850);
WIRE 16 -1 (-3325 5075)(-3325 4850);
WIRE 16 -1 (-3600 4850)(-3325 4850);
WIRE 16 -1 (-3600 5075)(-3600 4850);
WIRE 16 -1 (-8275 4000)(-8275 3900);
WIRE 16 -1 (-8325 4000)(-8275 4000);
WIRE 16 -1 (-8325 4150)(-8325 4000);
WIRE 16 -1 (-8325 4000)(-8375 4000);
WIRE 16 -1 (-8375 4000)(-8375 3925);
WIRE 16 -1 (-8325 4150)(-8050 4150);
WIRE 16 -1 (-8325 4875)(-8325 4150);
WIRE 16 -1 (-7225 4875)(-8325 4875);
WIRE 16 -1 (-8325 4950)(-8325 4875);
WIRE 16 -1 (-7225 4875)(-6975 4875);
WIRE 16 -1 (-7225 4875)(-7225 4825);
WIRE 16 -1 (-6975 4875)(-6725 4875);
WIRE 16 -1 (-6975 4875)(-6975 4825);
WIRE 16 -1 (-6725 4875)(-6475 4875);
WIRE 16 -1 (-6725 4875)(-6725 4800);
WIRE 16 -1 (-6475 4875)(-6475 4800);
WIRE 16 -1 (-6475 4600)(-6475 4475);
WIRE 16 -1 (-6550 4475)(-6475 4475);
WIRE 16 -1 (-6725 4475)(-6550 4475);
WIRE 16 -1 (-6725 4600)(-6725 4475);
WIRE 16 -1 (-6975 4475)(-6725 4475);
WIRE 16 -1 (-6975 4625)(-6975 4475);
WIRE 16 -1 (-7225 4475)(-6975 4475);
WIRE 16 -1 (-7225 4625)(-7225 4475);
WIRE 16 -1 (-5325 3800)(-5325 3700);
WIRE 16 -1 (-5600 3700)(-5325 3700);
WIRE 16 -1 (-5600 3800)(-5600 3700);
WIRE 16 -1 (-5850 3700)(-5600 3700);
WIRE 16 -1 (-5850 3800)(-5850 3700);
WIRE 16 -1 (-6100 3700)(-5850 3700);
WIRE 16 -1 (-6100 3800)(-6100 3700);
WIRE 16 -1 (-6325 3700)(-6100 3700);
WIRE 16 -1 (-6525 3700)(-6325 3700);
WIRE 16 -1 (-6325 3800)(-6325 3700);
WIRE 16 -1 (-6325 3700)(-6325 3625);
WIRE 16 -1 (-6525 3800)(-6525 3700);
WIRE 16 -1 (-6750 3700)(-6525 3700);
WIRE 16 -1 (-6750 3800)(-6750 3700);
WIRE 16 -1 (-6950 3700)(-6750 3700);
WIRE 16 -1 (-6950 3800)(-6950 3700);
WIRE 16 -1 (-7150 3700)(-6950 3700);
WIRE 16 -1 (-7150 3800)(-7150 3700);
WIRE 16 -1 (-7375 3700)(-7150 3700);
WIRE 16 -1 (-7375 3800)(-7375 3700);
WIRE 16 -1 (-3375 1850)(-3375 1725);
WIRE 16 -1 (-3375 1725)(-3075 1725);
WIRE 16 -1 (-3075 1725)(-2850 1725);
WIRE 16 -1 (-3075 1850)(-3075 1725);
WIRE 16 -1 (-2850 1725)(-2600 1725);
WIRE 16 -1 (-2850 1850)(-2850 1725);
WIRE 16 -1 (-2600 1725)(-2350 1725);
WIRE 16 -1 (-2600 1850)(-2600 1725);
WIRE 16 -1 (-2350 1725)(-2075 1725);
WIRE 16 -1 (-2350 1850)(-2350 1725);
WIRE 16 -1 (-1800 1725)(-2075 1725);
WIRE 16 -1 (-2075 1850)(-2075 1725);
WIRE 16 -1 (-1800 1725)(-1550 1725);
WIRE 16 -1 (-1800 1850)(-1800 1725);
WIRE 16 -1 (-1275 1725)(-1550 1725);
WIRE 16 -1 (-1550 1850)(-1550 1725);
WIRE 16 -1 (-1550 1725)(-1550 1575);
WIRE 16 -1 (-975 1725)(-1275 1725);
WIRE 16 -1 (-1275 1850)(-1275 1725);
WIRE 16 -1 (-675 1725)(-975 1725);
WIRE 16 -1 (-975 1850)(-975 1725);
WIRE 16 -1 (-675 1850)(-675 1725);
WIRE 16 -1 (-6675 3050)(-6675 2900);
WIRE 16 -1 (-6950 3050)(-6675 3050);
WIRE 16 -1 (-6950 2925)(-6950 3050);
WIRE 16 -1 (-6950 3050)(-7075 3050);
WIRE 16 -1 (-8325 3050)(-7075 3050);
WIRE 16 -1 (-7075 3050)(-7075 3150);
WIRE 16 -1 (-8325 3050)(-8325 3375);
WIRE 16 -1 (-8325 3375)(-8225 3375);
WIRE 16 -1 (-8325 3375)(-8325 3550);
WIRE 16 -1 (-8325 3550)(-8275 3550);
WIRE 16 -1 (-8375 3550)(-8325 3550);
WIRE 16 -1 (-8225 3475)(-8225 3375);
WIRE 16 -1 (-8225 3375)(-8225 3275);
WIRE 16 -1 (-8225 3275)(-7975 3275);
WIRE 16 -1 (-7975 3475)(-8225 3475);
WIRE 16 -1 (-8375 3550)(-8375 3725);
WIRE 16 -1 (-8275 3550)(-8275 3700);
WIRE 16 -1 (-6950 2725)(-6950 2550);
WIRE 16 -1 (-6950 2550)(-6675 2550);
WIRE 16 -1 (-6675 2700)(-6675 2550);
WIRE 16 -1 (-6675 2550)(-6675 2450);
WIRE 16 -1 (-3200 750)(-3200 625);
WIRE 16 -1 (-3200 625)(-2950 625);
WIRE 16 -1 (-2950 625)(-2650 625);
WIRE 16 -1 (-2950 750)(-2950 625);
WIRE 16 -1 (-2650 625)(-2500 625);
WIRE 16 -1 (-2650 750)(-2650 625);
WIRE 16 -1 (-2400 625)(-2500 625);
WIRE 16 -1 (-2500 625)(-2500 575);
WIRE 16 -1 (-2400 750)(-2400 625);
WIRE 16 -1 (-4475 2375)(-4475 2200);
WIRE 16 -1 (-4475 2200)(-4200 2200);
WIRE 16 -1 (-4475 1100)(-4475 2200);
WIRE 16 -1 (-4475 1100)(-3325 1100);
WIRE 16 -1 (-3325 1325)(-3325 1100);
WIRE 16 -1 (-3200 1100)(-3325 1100);
WIRE 16 -1 (-2950 1100)(-3200 1100);
WIRE 16 -1 (-3200 1100)(-3200 950);
WIRE 16 -1 (-2650 1100)(-2950 1100);
WIRE 16 -1 (-2950 1100)(-2950 950);
WIRE 16 -1 (-2400 1100)(-2650 1100);
WIRE 16 -1 (-2650 950)(-2650 1100);
WIRE 16 -1 (-2400 950)(-2400 1100);
DOT 1 (-1550 1725);
DOT 1 (-1550 2200);
DOT 1 (-1050 2325);
DOT 1 (-1800 2200);
DOT 1 (-2950 2875);
DOT 1 (-2500 3050);
DOT 1 (-3825 2875);
DOT 1 (-2050 3050);
DOT 1 (-2725 3050);
DOT 1 (-3425 3500);
DOT 1 (-2700 2325);
DOT 1 (-2350 2200);
DOT 1 (-2475 2875);
DOT 1 (-2975 3050);
DOT 1 (-2500 3500);
DOT 1 (-2975 3500);
DOT 1 (-3200 3500);
DOT 1 (-2725 3500);
DOT 1 (-2500 3650);
DOT 1 (-2500 4150);
DOT 1 (-3200 4150);
DOT 1 (-3425 4150);
DOT 1 (-2975 4150);
DOT 1 (-6950 3050);
DOT 1 (-7075 3050);
DOT 1 (-6950 3700);
DOT 1 (-3650 3500);
DOT 1 (-2975 3650);
DOT 1 (-2100 4850);
DOT 1 (-7375 4150);
DOT 1 (-6525 4150);
DOT 1 (-6325 3700);
DOT 1 (-2650 1100);
DOT 1 (-2275 3050);
DOT 1 (-1750 3650);
DOT 1 (-2275 3650);
DOT 1 (-3200 3650);
DOT 1 (-2275 3500);
DOT 1 (-2050 3500);
DOT 1 (-2275 4150);
DOT 1 (-1750 4150);
DOT 1 (-2050 4150);
DOT 1 (-1575 5400);
DOT 1 (-3000 5400);
DOT 1 (-2400 5400);
DOT 1 (-5850 3700);
DOT 1 (-6100 4150);
DOT 1 (-5850 4150);
DOT 1 (-5600 4150);
DOT 1 (-6750 3700);
DOT 1 (-6750 4150);
DOT 1 (-6950 4150);
DOT 1 (-6975 4875);
DOT 1 (-7150 4150);
DOT 1 (-7150 3700);
DOT 1 (-7475 4150);
DOT 1 (-8225 3375);
DOT 1 (-8325 4000);
DOT 1 (-8325 3375);
DOT 1 (-8325 3550);
DOT 1 (-6675 2550);
DOT 1 (-6525 3700);
DOT 1 (-4475 2200);
DOT 1 (-6325 4150);
DOT 1 (-6725 4475);
DOT 1 (-7225 4875);
DOT 1 (-6725 4875);
DOT 1 (-4475 5400);
DOT 1 (-2650 625);
DOT 1 (-2850 1725);
DOT 1 (-2350 1725);
DOT 1 (-3825 2200);
DOT 1 (-3425 2325);
DOT 1 (-3825 3500);
DOT 1 (-3650 2875);
DOT 1 (-3425 3050);
DOT 1 (-3425 3650);
DOT 1 (-3075 2200);
DOT 1 (-3175 2325);
DOT 1 (-2950 2325);
DOT 1 (-2600 2200);
DOT 1 (-2725 3650);
DOT 1 (-2050 3650);
DOT 1 (-1450 3650);
DOT 1 (-3825 4150);
DOT 1 (-3650 4150);
DOT 1 (-3325 4850);
DOT 1 (-3325 5400);
DOT 1 (-3000 4850);
DOT 1 (-2400 4850);
DOT 1 (-2700 5400);
DOT 1 (-1825 4850);
DOT 1 (-1825 5400);
DOT 1 (-2100 5400);
DOT 1 (-1575 4850);
DOT 1 (-1375 4850);
DOT 1 (-8325 4875);
DOT 1 (-7575 3375);
DOT 1 (-3600 5400);
DOT 1 (-3375 2200);
DOT 1 (-4475 4150);
DOT 1 (-6975 4475);
DOT 1 (-2700 4850);
DOT 1 (-6100 3700);
DOT 1 (-3200 3050);
DOT 1 (-8325 4150);
DOT 1 (-3075 1725);
DOT 1 (-1800 1725);
DOT 1 (-2850 2200);
DOT 1 (-2075 2200);
DOT 1 (-2500 625);
DOT 1 (-2600 1725);
DOT 1 (-2725 4150);
DOT 1 (-5600 3700);
DOT 1 (-2475 2325);
DOT 1 (-2250 2325);
DOT 1 (-2075 1725);
DOT 1 (-1050 3050);
DOT 1 (-1575 3050);
DOT 1 (-3325 1100);
DOT 1 (-3200 1100);
DOT 1 (-2950 1100);
DOT 1 (-2950 625);
DOT 1 (-3425 2875);
DOT 1 (-2250 2875);
DOT 1 (-1825 3500);
DOT 1 (-1825 3050);
DOT 1 (-1975 2875);
DOT 1 (-1975 2325);
DOT 1 (-1700 2325);
DOT 1 (-975 1725);
DOT 1 (-1275 2200);
DOT 1 (-1275 1725);
DOT 1 (-975 2200);
DOT 1 (-2700 2875);
DOT 1 (-3175 2875);
QUIT
